-- pcdb file, Rev:1.0 written by Allegro Design Entry HDL 17.2-2016 S067 (3860444) 4/26/2020 on Mon Sep 05 14:58:10 2022
#ISCELL
  cls table_cover *
  *
#ISCELL
  cls table_toc_cl *
  *
#ISCELL
  cls sheet_a1 *
  *
#ISCELL
  cls sheet_a1 *
  *
#ISCELL
  cls sheet_a1 *
  *
#ISCELL
  cls sheet_a1 *
  *
#ISCELL
  cls sheet_a1 *
  *
#ISCELL
  cls sheet_a1 *
  *
#ISCELL
  cls sheet_a1 *
  *
#ISCELL
  cls gnd_sg *
  page3_i1
#ISCELL
  cls offpage_out *
  page3_i10
#CELL
  stdlogic g220_10198_01 *
  page3_i100
#CELL
  passive resistor *
  page3_i103
#ISCELL
  cls offpage_bi *
  page3_i109
#ISCELL
  cls offpage_out *
  page3_i11
#ISCELL
  cls offpage_out *
  page3_i110
#ISCELL
  cls vcc *
  page3_i111
#ISCELL
  cls vcc *
  page3_i112
#ISCELL
  cls offpage_in *
  page3_i113
#CELL
  passive resistor *
  page3_i114
#CELL
  passive capacitor *
  page3_i115
#CELL
  passive capacitor *
  page3_i116
#CELL
  passive capacitor *
  page3_i117
#CELL
  passive capacitor *
  page3_i118
#CELL
  passive capacitor *
  page3_i119
#ISCELL
  cls offpage_in *
  page3_i12
#CELL
  passive capacitor *
  page3_i120
#CELL
  passive capacitor *
  page3_i121
#CELL
  passive resistor *
  page3_i122
#ISCELL
  cls offpage_out *
  page3_i123
#CELL
  passive capacitor *
  page3_i124
#ISCELL
  cls gnd_sg *
  page3_i125
#CELL
  passive capacitor *
  page3_i126
#CELL
  passive capacitor *
  page3_i127
#ISCELL
  cls gnd_sg *
  page3_i128
#CELL
  passive capacitor *
  page3_i129
#ISCELL
  cls offpage_out *
  page3_i13
#ISCELL
  cls vcc *
  page3_i130
#ISCELL
  cls vcc *
  page3_i131
#CELL
  passive ferritebead *
  page3_i132
#ISCELL
  cls vcc *
  page3_i133
#CELL
  stdlogic 74lvc1g07_sc70_5 *
  page3_i134
#CELL
  stdlogic 74lvc1g07_sc70_5 *
  page3_i135
#ISCELL
  cls offpage_in *
  page3_i138
#CELL
  analog tps3808g18dbvr_sot23_6 *
  page3_i139
#ISCELL
  cls offpage_out *
  page3_i14
#ISCELL
  cls vcc *
  page3_i140
#ISCELL
  cls offpage_out *
  page3_i141
#CELL
  passive resistor *
  page3_i144
#CELL
  passive resistor *
  page3_i148
#ISCELL
  cls vcc *
  page3_i149
#CELL
  passive resistor *
  page3_i15
#ISCELL
  cls gnd_sg *
  page3_i150
#CELL
  passive resistor *
  page3_i151
#CELL
  passive capacitor *
  page3_i152
#CELL
  passive resistor *
  page3_i153
#ISCELL
  cls offpage_out *
  page3_i154
#ISCELL
  cls offpage_in *
  page3_i155
#CELL
  passive resistor *
  page3_i16
#ISCELL
  cls gnd_sg *
  page3_i18
#ISCELL
  cls vcc *
  page3_i19
#ISCELL
  cls gnd_sg *
  page3_i20
#ISCELL
  cls vcc *
  page3_i23
#ISCELL
  cls vcc *
  page3_i24
#ISCELL
  cls vcc *
  page3_i25
#ISCELL
  cls gnd_sg *
  page3_i26
#CELL
  passive capacitor *
  page3_i35
#CELL
  passive capacitor *
  page3_i36
#CELL
  passive capacitor *
  page3_i37
#ISCELL
  cls offpage_in *
  page3_i39
#CELL
  passive capacitor *
  page3_i4
#ISCELL
  cls offpage_in *
  page3_i40
#ISCELL
  cls offpage_in *
  page3_i41
#ISCELL
  cls offpage_in *
  page3_i42
#ISCELL
  cls offpage_in *
  page3_i43
#ISCELL
  cls offpage_in *
  page3_i44
#ISCELL
  cls offpage_in *
  page3_i45
#ISCELL
  cls offpage_in *
  page3_i46
#ISCELL
  cls offpage_out *
  page3_i47
#ISCELL
  cls offpage_out *
  page3_i48
#ISCELL
  cls vcc *
  page3_i49
#ISCELL
  cls offpage_out *
  page3_i5
#CELL
  passive resistor *
  page3_i51
#CELL
  passive resistor *
  page3_i52
#CELL
  passive resistor *
  page3_i53
#CELL
  passive resistor *
  page3_i54
#ISCELL
  cls offpage_in *
  page3_i55
#ISCELL
  cls offpage_out *
  page3_i56
#ISCELL
  cls offpage_in *
  page3_i57
#ISCELL
  cls offpage_out *
  page3_i58
#ISCELL
  cls offpage_out *
  page3_i59
#ISCELL
  cls offpage_in *
  page3_i6
#CELL
  connector conn_64p_gf *
  page3_i61
#CELL
  passive resistor *
  page3_i62
#CELL
  passive resistor *
  page3_i63
#ISCELL
  cls offpage_out *
  page3_i7
#ISCELL
  cls offpage_out *
  page3_i8
#ISCELL
  cls offpage_bi *
  page3_i81
#ISCELL
  cls offpage_bi *
  page3_i82
#ISCELL
  cls offpage_bi *
  page3_i86
#ISCELL
  cls offpage_in *
  page3_i87
#ISCELL
  cls offpage_out *
  page3_i9
#ISCELL
  cls gnd_sg *
  page3_i91
#CELL
  passive capacitor *
  page3_i92
#ISCELL
  cls gnd_sg *
  page3_i94
#ISCELL
  cls sheet_a1 *
  *
#ISCELL
  cls offpage_out *
  page127_i101
#ISCELL
  cls gnd_sg *
  page127_i106
#ISCELL
  cls gnd_sg *
  page127_i130
#ISCELL
  cls offpage_out *
  page127_i137
#ISCELL
  cls offpage_in *
  page127_i189
#ISCELL
  cls offpage_in *
  page127_i190
#ISCELL
  cls offpage_in *
  page127_i191
#ISCELL
  cls offpage_in *
  page127_i193
#ISCELL
  cls offpage_in *
  page127_i194
#ISCELL
  cls offpage_in *
  page127_i195
#CELL
  pld xc7a200t_2fbg484c_fbg484 *
  page127_i232
#ISCELL
  cls vcc *
  page127_i243
#ISCELL
  cls offpage_out *
  page127_i260
#ISCELL
  cls offpage_out *
  page127_i261
#ISCELL
  cls offpage_in *
  page127_i267
#ISCELL
  cls offpage_in *
  page127_i268
#ISCELL
  cls offpage_in *
  page127_i293
#ISCELL
  cls offpage_in *
  page127_i294
#ISCELL
  cls offpage_in *
  page127_i295
#ISCELL
  cls offpage_in *
  page127_i296
#ISCELL
  cls offpage_in *
  page127_i297
#ISCELL
  cls offpage_in *
  page127_i298
#ISCELL
  cls offpage_in *
  page127_i299
#ISCELL
  cls offpage_in *
  page127_i300
#ISCELL
  cls offpage_out *
  page127_i302
#ISCELL
  cls offpage_out *
  page127_i303
#ISCELL
  cls offpage_out *
  page127_i305
#ISCELL
  cls offpage_out *
  page127_i306
#ISCELL
  cls offpage_out *
  page127_i307
#ISCELL
  cls offpage_out *
  page127_i308
#CELL
  passive resistor *
  page127_i329
#CELL
  passive resistor *
  page127_i330
#CELL
  passive resistor *
  page127_i331
#CELL
  passive resistor *
  page127_i332
#CELL
  passive resistor *
  page127_i333
#CELL
  passive resistor *
  page127_i334
#CELL
  passive resistor *
  page127_i337
#CELL
  passive resistor *
  page127_i338
#CELL
  passive resistor *
  page127_i339
#ISCELL
  cls offpage_in *
  page127_i361
#ISCELL
  cls offpage_in *
  page127_i362
#ISCELL
  cls vcc *
  page127_i385
#ISCELL
  cls vcc *
  page127_i389
#ISCELL
  cls vcc *
  page127_i390
#CELL
  passive resistor *
  page127_i391
#CELL
  passive resistor *
  page127_i392
#CELL
  passive resistor *
  page127_i393
#CELL
  passive resistor *
  page127_i394
#CELL
  passive resistor *
  page127_i396
#CELL
  passive resistor *
  page127_i397
#ISCELL
  cls gnd_sg *
  page127_i398
#ISCELL
  cls offpage_out *
  page127_i399
#ISCELL
  cls offpage_out *
  page127_i400
#ISCELL
  cls offpage_out *
  page127_i401
#CELL
  passive resistor *
  page127_i402
#CELL
  passive resistor *
  page127_i403
#CELL
  passive resistor *
  page127_i404
#CELL
  passive resistor *
  page127_i405
#CELL
  passive resistor *
  page127_i406
#CELL
  passive resistor *
  page127_i407
#ISCELL
  cls vcc *
  page127_i409
#ISCELL
  cls offpage_in *
  page127_i410
#ISCELL
  cls offpage_in *
  page127_i426
#CELL
  connector g200_10283_01 *
  page127_i427
#ISCELL
  cls offpage_out *
  page127_i428
#ISCELL
  cls offpage_out *
  page127_i429
#ISCELL
  cls offpage_out *
  page127_i430
#ISCELL
  cls offpage_in *
  page127_i431
#CELL
  passive resistor *
  page127_i432
#ISCELL
  cls vcc *
  page127_i433
#CELL
  passive resistor *
  page127_i434
#CELL
  passive resistor *
  page127_i435
#CELL
  passive resistor *
  page127_i436
#CELL
  passive resistor *
  page127_i437
#CELL
  passive resistor *
  page127_i438
#CELL
  passive resistor *
  page127_i439
#CELL
  passive resistor *
  page127_i440
#ISCELL
  cls gnd_sg *
  page127_i441
#CELL
  discrete diode_4_v1 *
  page127_i442
#CELL
  discrete diode_4_v1 *
  page127_i443
#ISCELL
  cls gnd_sg *
  page127_i444
#ISCELL
  cls gnd_sg *
  page127_i445
#CELL
  passive resistor *
  page127_i446
#ISCELL
  cls vcc *
  page127_i447
#ISCELL
  cls offpage_in *
  page127_i452
#ISCELL
  cls offpage_in *
  page127_i453
#ISCELL
  cls offpage_out *
  page127_i454
#ISCELL
  cls offpage_in *
  page127_i455
#CELL
  memory mt25ql128aba1ese_sop8 *
  page127_i456
#ISCELL
  cls vcc *
  page127_i457
#ISCELL
  cls offpage_bi *
  page127_i458
#ISCELL
  cls offpage_bi *
  page127_i459
#ISCELL
  cls offpage_bi *
  page127_i460
#ISCELL
  cls offpage_bi *
  page127_i461
#CELL
  passive resistor *
  page127_i462
#CELL
  passive resistor *
  page127_i463
#CELL
  passive resistor *
  page127_i464
#CELL
  passive resistor *
  page127_i465
#CELL
  passive resistor *
  page127_i466
#CELL
  passive resistor *
  page127_i467
#CELL
  passive resistor *
  page127_i468
#CELL
  passive resistor *
  page127_i469
#CELL
  passive resistor *
  page127_i470
#CELL
  passive resistor *
  page127_i471
#CELL
  passive capacitor *
  page127_i472
#CELL
  passive capacitor *
  page127_i473
#ISCELL
  cls vcc *
  page127_i474
#ISCELL
  cls offpage_in *
  page127_i475
#ISCELL
  cls offpage_in *
  page127_i476
#ISCELL
  cls gnd_sg *
  page127_i477
#ISCELL
  cls gnd_sg *
  page127_i478
#ISCELL
  cls gnd_sg *
  page127_i479
#ISCELL
  cls offpage_in *
  page127_i480
#ISCELL
  cls offpage_in *
  page127_i481
#ISCELL
  cls offpage_out *
  page127_i71
#ISCELL
  cls offpage_out *
  page127_i72
#ISCELL
  cls offpage_out *
  page127_i73
#ISCELL
  cls gnd_sg *
  page127_i75
#ISCELL
  cls sheet_a1 *
  *
#ISCELL
  cls offpage_bi *
  page161_i100
#ISCELL
  cls offpage_bi *
  page161_i104
#ISCELL
  cls gnd_sg *
  page161_i136
#ISCELL
  cls offpage_out *
  page161_i139
#CELL
  passive resistor *
  page161_i140
#ISCELL
  cls offpage_out *
  page161_i143
#ISCELL
  cls offpage_in *
  page161_i16
#ISCELL
  cls offpage_in *
  page161_i17
#ISCELL
  cls offpage_bi *
  page161_i19
#CELL
  pld xc7a200t_2fbg484c_fbg484 *
  page161_i2
#CELL
  passive resistor *
  page161_i200
#CELL
  passive resistor *
  page161_i201
#ISCELL
  cls offpage_in *
  page161_i208
#ISCELL
  cls offpage_in *
  page161_i209
#ISCELL
  cls offpage_bi *
  page161_i224
#ISCELL
  cls offpage_out *
  page161_i225
#ISCELL
  cls offpage_out *
  page161_i226
#ISCELL
  cls offpage_bi *
  page161_i234
#ISCELL
  cls offpage_out *
  page161_i235
#ISCELL
  cls offpage_out *
  page161_i236
#ISCELL
  cls offpage_out *
  page161_i237
#ISCELL
  cls gnd_sg *
  page161_i238
#CELL
  passive resistor *
  page161_i239
#CELL
  passive resistor *
  page161_i240
#CELL
  passive resistor *
  page161_i241
#CELL
  passive resistor *
  page161_i242
#CELL
  passive resistor *
  page161_i244
#ISCELL
  cls gnd_sg *
  page161_i245
#CELL
  passive resistor *
  page161_i246
#CELL
  passive resistor *
  page161_i247
#ISCELL
  cls vcc *
  page161_i248
#ISCELL
  cls vcc *
  page161_i249
#ISCELL
  cls gnd_sg *
  page161_i250
#CELL
  passive resistor *
  page161_i251
#CELL
  passive resistor *
  page161_i252
#CELL
  passive resistor *
  page161_i253
#ISCELL
  cls offpage_bi *
  page161_i254
#ISCELL
  cls offpage_bi *
  page161_i255
#ISCELL
  cls offpage_bi *
  page161_i256
#ISCELL
  cls offpage_bi *
  page161_i257
#CELL
  passive resistor *
  page161_i258
#CELL
  passive resistor *
  page161_i259
#CELL
  passive resistor *
  page161_i260
#CELL
  passive resistor *
  page161_i261
#ISCELL
  cls offpage_out *
  page161_i262
#CELL
  passive resistor *
  page161_i263
#ISCELL
  cls offpage_in *
  page161_i27
#ISCELL
  cls offpage_out *
  page161_i28
#ISCELL
  cls offpage_in *
  page161_i34
#ISCELL
  cls offpage_out *
  page161_i35
#ISCELL
  cls offpage_in *
  page161_i36
#ISCELL
  cls offpage_out *
  page161_i37
#ISCELL
  cls offpage_in *
  page161_i38
#ISCELL
  cls offpage_out *
  page161_i39
#ISCELL
  cls offpage_out *
  page161_i42
#ISCELL
  cls offpage_in *
  page161_i43
#ISCELL
  cls offpage_in *
  page161_i44
#ISCELL
  cls offpage_out *
  page161_i54
#ISCELL
  cls offpage_in *
  page161_i55
#ISCELL
  cls offpage_in *
  page161_i60
#ISCELL
  cls offpage_out *
  page161_i61
#ISCELL
  cls offpage_out *
  page161_i62
#ISCELL
  cls offpage_bi *
  page161_i70
#ISCELL
  cls offpage_out *
  page161_i9
#ISCELL
  cls sheet_a1 *
  *
#CELL
  pld xc7a200t_2fbg484c_fbg484 *
  page162_i228
#ISCELL
  cls offpage_out *
  page162_i230
#ISCELL
  cls offpage_out *
  page162_i231
#ISCELL
  cls offpage_out *
  page162_i236
#ISCELL
  cls offpage_out *
  page162_i237
#ISCELL
  cls offpage_in *
  page162_i239
#ISCELL
  cls offpage_bi *
  page162_i318
#ISCELL
  cls offpage_bi *
  page162_i319
#ISCELL
  cls offpage_bi *
  page162_i320
#ISCELL
  cls offpage_bi *
  page162_i321
#ISCELL
  cls offpage_bi *
  page162_i322
#ISCELL
  cls offpage_bi *
  page162_i323
#ISCELL
  cls offpage_bi *
  page162_i324
#ISCELL
  cls offpage_bi *
  page162_i325
#ISCELL
  cls offpage_bi *
  page162_i326
#ISCELL
  cls offpage_bi *
  page162_i327
#ISCELL
  cls offpage_out *
  page162_i338
#ISCELL
  cls offpage_in *
  page162_i339
#ISCELL
  cls offpage_out *
  page162_i346
#ISCELL
  cls offpage_out *
  page162_i347
#ISCELL
  cls offpage_in *
  page162_i354
#ISCELL
  cls offpage_in *
  page162_i355
#ISCELL
  cls offpage_in *
  page162_i356
#ISCELL
  cls offpage_in *
  page162_i399
#ISCELL
  cls offpage_in *
  page162_i400
#ISCELL
  cls offpage_in *
  page162_i401
#ISCELL
  cls offpage_out *
  page162_i428
#ISCELL
  cls offpage_out *
  page162_i429
#ISCELL
  cls offpage_out *
  page162_i430
#ISCELL
  cls offpage_out *
  page162_i431
#ISCELL
  cls offpage_in *
  page162_i432
#ISCELL
  cls offpage_out *
  page162_i433
#ISCELL
  cls offpage_out *
  page162_i434
#ISCELL
  cls offpage_out *
  page162_i435
#ISCELL
  cls offpage_out *
  page162_i436
#ISCELL
  cls offpage_out *
  page162_i437
#ISCELL
  cls offpage_out *
  page162_i438
#ISCELL
  cls offpage_out *
  page162_i439
#ISCELL
  cls offpage_out *
  page162_i440
#ISCELL
  cls offpage_out *
  page162_i441
#ISCELL
  cls offpage_out *
  page162_i442
#ISCELL
  cls offpage_out *
  page162_i443
#ISCELL
  cls offpage_out *
  page162_i444
#ISCELL
  cls offpage_out *
  page162_i445
#ISCELL
  cls offpage_out *
  page162_i446
#ISCELL
  cls offpage_out *
  page162_i447
#ISCELL
  cls offpage_out *
  page162_i448
#ISCELL
  cls offpage_out *
  page162_i449
#ISCELL
  cls offpage_out *
  page162_i450
#ISCELL
  cls offpage_out *
  page162_i451
#ISCELL
  cls offpage_out *
  page162_i452
#ISCELL
  cls offpage_out *
  page162_i453
#ISCELL
  cls offpage_in *
  page162_i454
#ISCELL
  cls offpage_out *
  page162_i455
#ISCELL
  cls offpage_out *
  page162_i456
#ISCELL
  cls offpage_out *
  page162_i473
#ISCELL
  cls offpage_out *
  page162_i474
#ISCELL
  cls offpage_out *
  page162_i475
#ISCELL
  cls offpage_bi *
  page162_i476
#ISCELL
  cls offpage_bi *
  page162_i477
#ISCELL
  cls offpage_bi *
  page162_i478
#ISCELL
  cls offpage_bi *
  page162_i479
#ISCELL
  cls offpage_bi *
  page162_i480
#ISCELL
  cls offpage_bi *
  page162_i481
#ISCELL
  cls offpage_bi *
  page162_i482
#ISCELL
  cls offpage_bi *
  page162_i483
#ISCELL
  cls sheet_a1 *
  *
#CELL
  pld xc7a200t_2fbg484c_fbg484 *
  page163_i1
#ISCELL
  cls offpage_bi *
  page163_i112
#ISCELL
  cls offpage_bi *
  page163_i113
#ISCELL
  cls offpage_bi *
  page163_i114
#ISCELL
  cls offpage_bi *
  page163_i115
#CELL
  passive resistor *
  page163_i120
#ISCELL
  cls gnd_sg *
  page163_i124
#ISCELL
  cls vcc *
  page163_i125
#CELL
  passive resistor *
  page163_i126
#CELL
  passive resistor *
  page163_i127
#CELL
  passive resistor *
  page163_i128
#ISCELL
  cls vcc *
  page163_i130
#ISCELL
  cls gnd_sg *
  page163_i131
#CELL
  passive resistor *
  page163_i132
#CELL
  passive resistor *
  page163_i133
#CELL
  passive resistor *
  page163_i134
#CELL
  passive resistor *
  page163_i135
#ISCELL
  cls offpage_bi *
  page163_i14
#ISCELL
  cls offpage_bi *
  page163_i15
#ISCELL
  cls offpage_bi *
  page163_i16
#ISCELL
  cls offpage_bi *
  page163_i17
#ISCELL
  cls offpage_bi *
  page163_i18
#ISCELL
  cls offpage_bi *
  page163_i19
#ISCELL
  cls offpage_in *
  page163_i30
#ISCELL
  cls offpage_in *
  page163_i31
#ISCELL
  cls offpage_out *
  page163_i32
#ISCELL
  cls offpage_out *
  page163_i33
#ISCELL
  cls offpage_out *
  page163_i34
#ISCELL
  cls offpage_out *
  page163_i35
#CELL
  passive resistor *
  page163_i36
#CELL
  passive resistor *
  page163_i37
#CELL
  passive resistor *
  page163_i38
#CELL
  passive resistor *
  page163_i39
#ISCELL
  cls offpage_in *
  page163_i4
#ISCELL
  cls offpage_bi *
  page163_i40
#ISCELL
  cls offpage_bi *
  page163_i41
#ISCELL
  cls offpage_bi *
  page163_i42
#ISCELL
  cls offpage_bi *
  page163_i43
#ISCELL
  cls offpage_bi *
  page163_i44
#ISCELL
  cls offpage_bi *
  page163_i45
#ISCELL
  cls offpage_bi *
  page163_i46
#ISCELL
  cls offpage_bi *
  page163_i47
#ISCELL
  cls offpage_bi *
  page163_i48
#ISCELL
  cls offpage_bi *
  page163_i49
#ISCELL
  cls offpage_in *
  page163_i5
#ISCELL
  cls sheet_a1 *
  *
#ISCELL
  cls gnd_sg *
  page164_i1
#CELL
  passive ferritebead *
  page164_i102
#ISCELL
  cls gnd_sg *
  page164_i134
#ISCELL
  cls vcc *
  page164_i135
#ISCELL
  cls gnd_sg *
  page164_i137
#CELL
  pld xc7a200t_2fbg484c_fbg484 *
  page164_i138
#CELL
  passive ferritebead *
  page164_i139
#CELL
  passive capacitor *
  page164_i172
#CELL
  passive capacitor *
  page164_i173
#CELL
  passive capacitor *
  page164_i174
#CELL
  passive capacitor *
  page164_i176
#CELL
  passive capacitor *
  page164_i177
#CELL
  passive capacitor *
  page164_i178
#CELL
  passive capacitor *
  page164_i182
#CELL
  passive capacitor *
  page164_i183
#CELL
  passive capacitor *
  page164_i184
#CELL
  passive capacitor *
  page164_i185
#CELL
  passive capacitor *
  page164_i186
#CELL
  passive capacitor *
  page164_i187
#CELL
  passive capacitor *
  page164_i188
#CELL
  passive capacitor *
  page164_i189
#CELL
  passive capacitor *
  page164_i190
#CELL
  passive capacitor *
  page164_i191
#CELL
  passive capacitor *
  page164_i192
#CELL
  passive capacitor *
  page164_i193
#CELL
  passive capacitor *
  page164_i194
#CELL
  passive capacitor *
  page164_i195
#CELL
  passive capacitor *
  page164_i196
#CELL
  passive capacitor *
  page164_i197
#CELL
  passive capacitor *
  page164_i198
#CELL
  passive capacitor *
  page164_i199
#CELL
  passive capacitor *
  page164_i200
#CELL
  passive capacitor *
  page164_i201
#CELL
  passive capacitor *
  page164_i202
#CELL
  passive capacitor *
  page164_i203
#CELL
  passive capacitor *
  page164_i204
#CELL
  passive capacitor *
  page164_i205
#CELL
  passive capacitor *
  page164_i206
#CELL
  passive capacitor *
  page164_i207
#CELL
  passive capacitor *
  page164_i208
#CELL
  passive capacitor *
  page164_i209
#CELL
  passive capacitor *
  page164_i210
#CELL
  passive capacitor *
  page164_i211
#CELL
  passive capacitor *
  page164_i212
#CELL
  passive capacitor *
  page164_i213
#CELL
  passive capacitor *
  page164_i214
#CELL
  passive capacitor *
  page164_i215
#CELL
  passive capacitor *
  page164_i216
#CELL
  passive capacitor *
  page164_i217
#CELL
  passive capacitor *
  page164_i218
#CELL
  passive capacitor *
  page164_i219
#CELL
  passive capacitor *
  page164_i220
#CELL
  passive capacitor *
  page164_i221
#CELL
  passive capacitor *
  page164_i222
#CELL
  passive capacitor *
  page164_i223
#CELL
  passive capacitor *
  page164_i224
#CELL
  passive capacitor *
  page164_i225
#CELL
  passive capacitor *
  page164_i226
#CELL
  passive capacitor *
  page164_i227
#CELL
  passive capacitor *
  page164_i228
#CELL
  passive capacitor *
  page164_i229
#CELL
  passive capacitor *
  page164_i230
#CELL
  passive capacitor *
  page164_i231
#CELL
  passive capacitor *
  page164_i232
#CELL
  passive capacitor *
  page164_i233
#CELL
  passive capacitor *
  page164_i234
#CELL
  passive capacitor *
  page164_i235
#CELL
  passive capacitor *
  page164_i236
#CELL
  passive capacitor *
  page164_i237
#CELL
  passive capacitor *
  page164_i238
#CELL
  passive capacitor *
  page164_i239
#CELL
  passive capacitor *
  page164_i240
#CELL
  passive capacitor *
  page164_i241
#CELL
  passive capacitor *
  page164_i242
#CELL
  passive capacitor *
  page164_i243
#CELL
  passive capacitor *
  page164_i245
#CELL
  passive capacitor *
  page164_i246
#CELL
  passive capacitor *
  page164_i248
#CELL
  passive capacitor *
  page164_i249
#CELL
  passive capacitor *
  page164_i250
#CELL
  passive capacitor *
  page164_i251
#CELL
  passive capacitor *
  page164_i252
#CELL
  passive capacitor *
  page164_i253
#CELL
  passive capacitor *
  page164_i254
#CELL
  passive capacitor *
  page164_i255
#CELL
  passive capacitor *
  page164_i256
#CELL
  passive capacitor *
  page164_i257
#CELL
  passive capacitor *
  page164_i258
#CELL
  passive capacitor *
  page164_i259
#CELL
  passive capacitor *
  page164_i260
#CELL
  passive capacitor *
  page164_i264
#CELL
  passive capacitor *
  page164_i265
#CELL
  passive capacitor *
  page164_i266
#CELL
  passive capacitor *
  page164_i267
#CELL
  passive capacitor *
  page164_i268
#CELL
  passive capacitor *
  page164_i270
#CELL
  passive capacitor *
  page164_i271
#CELL
  passive capacitor *
  page164_i272
#CELL
  passive capacitor *
  page164_i273
#CELL
  passive capacitor *
  page164_i274
#CELL
  passive capacitor *
  page164_i275
#CELL
  passive capacitor *
  page164_i276
#CELL
  passive capacitor *
  page164_i277
#CELL
  passive capacitor *
  page164_i280
#CELL
  passive capacitor *
  page164_i281
#CELL
  passive capacitor *
  page164_i282
#CELL
  passive capacitor *
  page164_i283
#ISCELL
  cls vcc *
  page164_i284
#ISCELL
  cls vcc *
  page164_i285
#ISCELL
  cls vcc *
  page164_i286
#ISCELL
  cls vcc *
  page164_i287
#ISCELL
  cls vcc *
  page164_i288
#ISCELL
  cls vcc *
  page164_i289
#CELL
  passive capacitor *
  page164_i290
#CELL
  passive capacitor *
  page164_i291
#CELL
  passive capacitor *
  page164_i292
#ISCELL
  cls gnd_sg *
  page164_i293
#CELL
  passive ferritebead *
  page164_i36
#CELL
  passive ferritebead *
  page164_i37
#ISCELL
  cls gnd_sg *
  page164_i5
#ISCELL
  cls gnd_sg *
  page164_i59
#ISCELL
  cls gnd_sg *
  page164_i64
#ISCELL
  cls gnd_sg *
  page164_i73
#ISCELL
  cls sheet_a1 *
  *
#ISCELL
  cls offpage_out *
  page522_i11
#ISCELL
  cls offpage_out *
  page522_i12
#ISCELL
  cls offpage_out *
  page522_i13
#ISCELL
  cls offpage_out *
  page522_i14
#CELL
  passive capacitor *
  page522_i142
#CELL
  passive capacitor *
  page522_i143
#CELL
  clock osc6p_v2 *
  page522_i144
#CELL
  clock osc6p_v2 *
  page522_i145
#CELL
  passive ferritebead *
  page522_i146
#CELL
  passive capacitor *
  page522_i147
#CELL
  passive resistor *
  page522_i149
#ISCELL
  cls gnd_sg *
  page522_i150
#CELL
  passive capacitor *
  page522_i151
#CELL
  passive capacitor *
  page522_i152
#CELL
  passive capacitor *
  page522_i153
#CELL
  passive capacitor *
  page522_i154
#ISCELL
  cls gnd_sg *
  page522_i155
#CELL
  passive resistor *
  page522_i156
#CELL
  passive capacitor *
  page522_i158
#CELL
  passive ferritebead *
  page522_i159
#CELL
  passive capacitor *
  page522_i160
#CELL
  passive capacitor *
  page522_i161
#ISCELL
  cls gnd_sg *
  page522_i167
#ISCELL
  cls gnd_sg *
  page522_i168
#CELL
  passive resistor *
  page522_i169
#CELL
  passive resistor *
  page522_i170
#ISCELL
  cls gnd_sg *
  page522_i171
#CELL
  passive resistor *
  page522_i172
#ISCELL
  cls gnd_sg *
  page522_i173
#CELL
  passive resistor *
  page522_i174
#ISCELL
  cls vcc *
  page522_i176
#ISCELL
  cls vcc *
  page522_i177
#ISCELL
  cls offpage_in *
  page522_i178
#ISCELL
  cls offpage_in *
  page522_i179
#ISCELL
  cls sheet_a1 *
  *
#CELL
  passive resistor *
  page5_i100
#CELL
  passive resistor *
  page5_i101
#CELL
  passive resistor *
  page5_i102
#CELL
  passive resistor *
  page5_i103
#ISCELL
  cls offpage_bi *
  page5_i104
#ISCELL
  cls offpage_in *
  page5_i105
#ISCELL
  cls offpage_bi *
  page5_i106
#ISCELL
  cls offpage_in *
  page5_i107
#CELL
  passive resistor *
  page5_i111
#CELL
  passive resistor *
  page5_i112
#ISCELL
  cls offpage_out *
  page5_i113
#ISCELL
  cls offpage_bi *
  page5_i114
#CELL
  passive resistor *
  page5_i115
#CELL
  passive resistor *
  page5_i116
#ISCELL
  cls offpage_out *
  page5_i117
#ISCELL
  cls offpage_bi *
  page5_i118
#ISCELL
  cls offpage_in *
  page5_i124
#CELL
  passive resistor *
  page5_i125
#CELL
  connector conn_hdr_2x2_m_s_smt *
  page5_i126
#CELL
  connector conn_hdr_2x2_m_s_smt *
  page5_i127
#ISCELL
  cls gnd_sg *
  page5_i128
#ISCELL
  cls offpage_in *
  page5_i129
#CELL
  passive resistor *
  page5_i130
#ISCELL
  cls gnd_sg *
  page5_i139
#ISCELL
  cls gnd_sg *
  page5_i147
#CELL
  memory 24lc16bt_i_st_tssop8 *
  page5_i148
#CELL
  memory 24lc16bt_i_st_tssop8 *
  page5_i151
#CELL
  passive resistor *
  page5_i153
#CELL
  passive resistor *
  page5_i156
#ISCELL
  cls vcc *
  page5_i159
#CELL
  passive resistor *
  page5_i160
#CELL
  passive resistor *
  page5_i161
#CELL
  passive resistor *
  page5_i162
#CELL
  passive resistor *
  page5_i165
#CELL
  passive resistor *
  page5_i166
#CELL
  passive resistor *
  page5_i167
#ISCELL
  cls vcc *
  page5_i168
#CELL
  passive resistor *
  page5_i169
#ISCELL
  cls gnd_sg *
  page5_i170
#CELL
  passive capacitor *
  page5_i171
#ISCELL
  cls vcc *
  page5_i172
#CELL
  passive resistor *
  page5_i173
#ISCELL
  cls offpage_in *
  page5_i174
#ISCELL
  cls offpage_bi *
  page5_i175
#ISCELL
  cls offpage_out *
  page5_i176
#ISCELL
  cls offpage_bi *
  page5_i177
#ISCELL
  cls offpage_in *
  page5_i178
#ISCELL
  cls offpage_in *
  page5_i179
#ISCELL
  cls offpage_in *
  page5_i180
#ISCELL
  cls offpage_in *
  page5_i181
#ISCELL
  cls offpage_out *
  page5_i25
#ISCELL
  cls offpage_bi *
  page5_i26
#ISCELL
  cls offpage_out *
  page5_i27
#ISCELL
  cls offpage_bi *
  page5_i28
#ISCELL
  cls offpage_out *
  page5_i29
#ISCELL
  cls offpage_bi *
  page5_i30
#ISCELL
  cls offpage_out *
  page5_i31
#ISCELL
  cls offpage_bi *
  page5_i32
#CELL
  interface pca9546apw_tssop16 *
  page5_i33
#CELL
  passive resistor *
  page5_i4
#CELL
  passive capacitor *
  page5_i45
#ISCELL
  cls offpage_bi *
  page5_i5
#CELL
  passive resistor *
  page5_i52
#ISCELL
  cls gnd_sg *
  page5_i53
#CELL
  interface pca9546apw_tssop16 *
  page5_i54
#CELL
  passive resistor *
  page5_i55
#ISCELL
  cls offpage_in *
  page5_i6
#CELL
  passive resistor *
  page5_i60
#CELL
  passive resistor *
  page5_i66
#CELL
  passive resistor *
  page5_i67
#CELL
  passive resistor *
  page5_i68
#CELL
  passive resistor *
  page5_i69
#CELL
  passive resistor *
  page5_i72
#ISCELL
  cls offpage_in *
  page5_i73
#ISCELL
  cls offpage_bi *
  page5_i74
#ISCELL
  cls vcc *
  page5_i76
#ISCELL
  cls vcc *
  page5_i77
#ISCELL
  cls vcc *
  page5_i78
#CELL
  passive resistor *
  page5_i80
#CELL
  passive resistor *
  page5_i81
#CELL
  passive resistor *
  page5_i82
#CELL
  passive resistor *
  page5_i83
#CELL
  passive resistor *
  page5_i84
#CELL
  passive resistor *
  page5_i85
#CELL
  passive resistor *
  page5_i86
#CELL
  passive resistor *
  page5_i87
#CELL
  passive resistor *
  page5_i88
#CELL
  memory at24mac402_sot23_5 *
  page5_i89
#ISCELL
  cls gnd_sg *
  page5_i9
#CELL
  passive resistor *
  page5_i90
#ISCELL
  cls vcc *
  page5_i91
#CELL
  passive capacitor *
  page5_i92
#ISCELL
  cls gnd_sg *
  page5_i93
#CELL
  passive resistor *
  page5_i94
#CELL
  passive resistor *
  page5_i95
#CELL
  passive resistor *
  page5_i96
#CELL
  passive resistor *
  page5_i97
#ISCELL
  cls gnd_sg *
  page5_i98
#ISCELL
  cls vcc *
  page5_i99
#ISCELL
  cls sheet_a1 *
  *
#CELL
  passive resistor *
  page6_i100
#ISCELL
  cls offpage_bi *
  page6_i12
#ISCELL
  cls offpage_bi *
  page6_i13
#CELL
  passive resistor *
  page6_i14
#CELL
  passive resistor *
  page6_i15
#CELL
  passive resistor *
  page6_i16
#ISCELL
  cls gnd_sg *
  page6_i29
#CELL
  passive resistor *
  page6_i30
#CELL
  passive resistor *
  page6_i31
#CELL
  passive resistor *
  page6_i32
#CELL
  passive resistor *
  page6_i33
#CELL
  interface lm75bdp_tssop8 *
  page6_i34
#CELL
  passive resistor *
  page6_i35
#CELL
  passive resistor *
  page6_i36
#CELL
  passive capacitor *
  page6_i37
#CELL
  interface lm75bdp_tssop8 *
  page6_i38
#CELL
  passive resistor *
  page6_i41
#ISCELL
  cls offpage_out *
  page6_i44
#ISCELL
  cls gnd_sg *
  page6_i45
#ISCELL
  cls vcc *
  page6_i56
#ISCELL
  cls vcc *
  page6_i57
#ISCELL
  cls vcc *
  page6_i58
#CELL
  interface lm75bdp_tssop8 *
  page6_i59
#CELL
  passive resistor *
  page6_i60
#ISCELL
  cls offpage_out *
  page6_i61
#ISCELL
  cls vcc *
  page6_i62
#ISCELL
  cls vcc *
  page6_i63
#CELL
  passive resistor *
  page6_i64
#CELL
  interface lm75bdp_tssop8 *
  page6_i66
#CELL
  passive capacitor *
  page6_i67
#ISCELL
  cls gnd_sg *
  page6_i68
#CELL
  passive resistor *
  page6_i69
#CELL
  passive resistor *
  page6_i70
#CELL
  passive resistor *
  page6_i71
#CELL
  passive resistor *
  page6_i72
#CELL
  passive resistor *
  page6_i73
#ISCELL
  cls gnd_sg *
  page6_i74
#CELL
  passive resistor *
  page6_i76
#ISCELL
  cls vcc *
  page6_i77
#CELL
  interface lm75bdp_tssop8 *
  page6_i81
#ISCELL
  cls offpage_out *
  page6_i82
#ISCELL
  cls vcc *
  page6_i83
#CELL
  passive resistor *
  page6_i84
#CELL
  passive resistor *
  page6_i85
#CELL
  passive resistor *
  page6_i86
#ISCELL
  cls vcc *
  page6_i87
#CELL
  passive resistor *
  page6_i88
#CELL
  interface lm75bdp_tssop8 *
  page6_i90
#CELL
  passive capacitor *
  page6_i91
#ISCELL
  cls gnd_sg *
  page6_i92
#CELL
  passive resistor *
  page6_i93
#CELL
  passive resistor *
  page6_i94
#CELL
  passive resistor *
  page6_i95
#ISCELL
  cls gnd_sg *
  page6_i96
#ISCELL
  cls vcc *
  page6_i98
#ISCELL
  cls sheet_a1 *
  *
#ISCELL
  cls offpage_in *
  page7_i1
#CELL
  passive resistor *
  page7_i13
#CELL
  passive resistor *
  page7_i14
#ISCELL
  cls vcc *
  page7_i15
#ISCELL
  cls vcc *
  page7_i17
#CELL
  passive capacitor *
  page7_i18
#CELL
  passive capacitor *
  page7_i19
#ISCELL
  cls offpage_bi *
  page7_i2
#ISCELL
  cls vcc *
  page7_i20
#CELL
  passive ferritebead *
  page7_i21
#ISCELL
  cls gnd_sg *
  page7_i22
#CELL
  passive capacitor *
  page7_i23
#ISCELL
  cls gnd_sg *
  page7_i25
#CELL
  passive resistor *
  page7_i3
#ISCELL
  cls offpage_in *
  page7_i32
#CELL
  passive resistor *
  page7_i33
#ISCELL
  cls gnd_sg *
  page7_i36
#ISCELL
  cls vcc *
  page7_i37
#CELL
  passive resistor *
  page7_i38
#CELL
  passive resistor *
  page7_i39
#CELL
  passive resistor *
  page7_i4
#CELL
  passive resistor *
  page7_i40
#CELL
  passive resistor *
  page7_i41
#ISCELL
  cls vcc *
  page7_i42
#ISCELL
  cls offpage_out *
  page7_i43
#CELL
  analog sht31a_dis_b10ks_dfn8 *
  page7_i44
#ISCELL
  cls offpage_in *
  page7_i45
#ISCELL
  cls offpage_out *
  page7_i46
#ISCELL
  cls gnd_sg *
  page7_i6
#CELL
  passive resistor *
  page7_i7
#CELL
  passive resistor *
  page7_i8
#ISCELL
  cls sheet_a1 *
  *
#ISCELL
  cls offpage_in *
  page8_i1
#ISCELL
  cls vcc *
  page8_i13
#CELL
  passive capacitor *
  page8_i16
#CELL
  passive ferritebead *
  page8_i18
#CELL
  passive capacitor *
  page8_i19
#ISCELL
  cls offpage_bi *
  page8_i2
#ISCELL
  cls gnd_sg *
  page8_i20
#CELL
  passive capacitor *
  page8_i21
#ISCELL
  cls vcc *
  page8_i22
#ISCELL
  cls vcc *
  page8_i23
#CELL
  analog icp_10100_lga10 *
  page8_i24
#ISCELL
  cls gnd_sg *
  page8_i25
#CELL
  passive resistor *
  page8_i3
#CELL
  passive resistor *
  page8_i30
#CELL
  passive resistor *
  page8_i31
#CELL
  passive resistor *
  page8_i32
#CELL
  passive resistor *
  page8_i33
#CELL
  passive resistor *
  page8_i34
#ISCELL
  cls gnd_sg *
  page8_i35
#ISCELL
  cls gnd_sg *
  page8_i38
#CELL
  passive capacitor *
  page8_i39
#CELL
  passive capacitor *
  page8_i41
#ISCELL
  cls offpage_bi *
  page8_i43
#ISCELL
  cls offpage_bi *
  page8_i44
#CELL
  passive resistor *
  page8_i5
#CELL
  stdlogic pca9508dp_tssop8 *
  page8_i51
#CELL
  stdlogic pca9508dp_tssop8 *
  page8_i52
#ISCELL
  cls gnd_sg *
  page8_i53
#ISCELL
  cls vcc *
  page8_i54
#ISCELL
  cls offpage_bi *
  page8_i57
#ISCELL
  cls offpage_out *
  page8_i58
#CELL
  passive resistor *
  page8_i6
#CELL
  passive resistor *
  page8_i63
#CELL
  passive resistor *
  page8_i64
#CELL
  passive resistor *
  page8_i69
#CELL
  passive resistor *
  page8_i7
#CELL
  passive resistor *
  page8_i70
#CELL
  passive resistor *
  page8_i71
#ISCELL
  cls vcc *
  page8_i72
#ISCELL
  cls vcc *
  page8_i73
#ISCELL
  cls sheet_a1 *
  *
#CELL
  passive resistor *
  page9_i11
#CELL
  passive resistor *
  page9_i12
#ISCELL
  cls gnd_sg *
  page9_i14
#CELL
  clock xtal_2 *
  page9_i16
#CELL
  passive capacitor *
  page9_i17
#ISCELL
  cls vcc *
  page9_i18
#ISCELL
  cls gnd_sg *
  page9_i19
#ISCELL
  cls vcc *
  page9_i20
#CELL
  passive capacitor *
  page9_i21
#CELL
  passive ferritebead *
  page9_i22
#CELL
  passive capacitor *
  page9_i23
#CELL
  passive capacitor *
  page9_i24
#CELL
  lsi bno080_lga_28 *
  page9_i29
#CELL
  passive resistor *
  page9_i31
#CELL
  passive resistor *
  page9_i32
#ISCELL
  cls offpage_out *
  page9_i34
#ISCELL
  cls offpage_in *
  page9_i35
#CELL
  passive resistor *
  page9_i37
#CELL
  passive resistor *
  page9_i38
#ISCELL
  cls offpage_in *
  page9_i4
#CELL
  passive resistor *
  page9_i41
#ISCELL
  cls offpage_in *
  page9_i42
#CELL
  passive resistor *
  page9_i43
#CELL
  passive resistor *
  page9_i44
#ISCELL
  cls gnd_sg *
  page9_i45
#ISCELL
  cls vcc *
  page9_i46
#CELL
  passive resistor *
  page9_i47
#ISCELL
  cls gnd_sg *
  page9_i48
#CELL
  passive resistor *
  page9_i49
#ISCELL
  cls offpage_bi *
  page9_i5
#CELL
  passive resistor *
  page9_i50
#CELL
  passive resistor *
  page9_i51
#CELL
  passive resistor *
  page9_i52
#CELL
  passive capacitor *
  page9_i53
#CELL
  passive capacitor *
  page9_i54
#CELL
  passive resistor *
  page9_i55
#ISCELL
  cls vcc *
  page9_i57
#CELL
  passive resistor *
  page9_i6
#CELL
  cls tp_piont *
  page9_i63
#CELL
  passive resistor *
  page9_i64
#CELL
  passive resistor *
  page9_i65
#CELL
  passive resistor *
  page9_i66
#CELL
  passive resistor *
  page9_i67
#CELL
  passive resistor *
  page9_i7
#CELL
  passive resistor *
  page9_i70
#CELL
  cls tp_piont *
  page9_i71
#CELL
  cls tp_piont *
  page9_i72
#ISCELL
  cls offpage_in *
  page9_i74
#ISCELL
  cls offpage_out *
  page9_i75
#ISCELL
  cls offpage_in *
  page9_i76
#ISCELL
  cls sheet_a1 *
  *
#ISCELL
  cls gnd_sg *
  page527_i1
#ISCELL
  cls gnd_sg *
  page527_i100
#CELL
  passive capacitor *
  page527_i103
#CELL
  stdlogic ts3usb3031rmgr_wqfn12 *
  page527_i108
#ISCELL
  cls offpage_bi *
  page527_i11
#ISCELL
  cls offpage_bi *
  page527_i12
#ISCELL
  cls offpage_bi *
  page527_i121
#ISCELL
  cls offpage_bi *
  page527_i122
#CELL
  passive resistor *
  page527_i123
#CELL
  passive resistor *
  page527_i124
#CELL
  passive resistor *
  page527_i126
#ISCELL
  cls gnd_sg *
  page527_i128
#CELL
  passive resistor *
  page527_i13
#ISCELL
  cls offpage_in *
  page527_i137
#ISCELL
  cls gnd_sg *
  page527_i139
#CELL
  passive resistor *
  page527_i14
#ISCELL
  cls gnd_sg *
  page527_i143
#CELL
  passive capacitor *
  page527_i144
#CELL
  stdlogic cl5003148a *
  page527_i146
#CELL
  stdlogic cl5003148a *
  page527_i147
#CELL
  passive resistor *
  page527_i149
#CELL
  passive capacitor *
  page527_i15
#CELL
  passive resistor *
  page527_i155
#CELL
  passive capacitor *
  page527_i16
#ISCELL
  cls offpage_in *
  page527_i161
#ISCELL
  cls offpage_bi *
  page527_i173
#ISCELL
  cls offpage_bi *
  page527_i174
#CELL
  passive resistor *
  page527_i175
#CELL
  passive resistor *
  page527_i176
#ISCELL
  cls offpage_bi *
  page527_i177
#ISCELL
  cls offpage_bi *
  page527_i178
#ISCELL
  cls offpage_bi *
  page527_i179
#ISCELL
  cls offpage_bi *
  page527_i180
#CELL
  passive resistor *
  page527_i187
#ISCELL
  cls vcc *
  page527_i190
#ISCELL
  cls vcc *
  page527_i191
#ISCELL
  cls vcc *
  page527_i192
#CELL
  connector conn_hdr_2x10_m_s_smt *
  page527_i193
#CELL
  connector conn_hdr_1x3_m_s_smt *
  page527_i198
#ISCELL
  cls gnd_sg *
  page527_i199
#CELL
  connector conn_usb_1x5_g2_gh4_f_ra_smt *
  page527_i2
#CELL
  passive resistor *
  page527_i200
#CELL
  passive resistor *
  page527_i201
#CELL
  passive resistor *
  page527_i202
#ISCELL
  cls offpage_out *
  page527_i203
#CELL
  passive resistor *
  page527_i204
#ISCELL
  cls offpage_in *
  page527_i205
#CELL
  passive resistor *
  page527_i206
#ISCELL
  cls offpage_out *
  page527_i207
#CELL
  passive capacitor *
  page527_i208
#CELL
  passive capacitor *
  page527_i209
#ISCELL
  cls vcc *
  page527_i21
#ISCELL
  cls offpage_in *
  page527_i210
#CELL
  passive resistor *
  page527_i211
#ISCELL
  cls vcc *
  page527_i212
#ISCELL
  cls gnd_sg *
  page527_i22
#CELL
  mech nut *
  page527_i220
#CELL
  passive resistor *
  page527_i221
#CELL
  passive resistor *
  page527_i222
#ISCELL
  cls vcc *
  page527_i223
#CELL
  mech nut *
  page527_i224
#CELL
  mech nut *
  page527_i225
#CELL
  mech nut *
  page527_i226
#CELL
  mech nut *
  page527_i227
#CELL
  mech nut *
  page527_i228
#CELL
  mech nut *
  page527_i229
#CELL
  passive resistor *
  page527_i23
#CELL
  mech nut *
  page527_i230
#CELL
  discrete powermos_3p_pch *
  page527_i231
#CELL
  discrete powermos_3p_nch_v1 *
  page527_i232
#CELL
  passive resistor *
  page527_i233
#ISCELL
  cls vcc *
  page527_i234
#ISCELL
  cls vcc *
  page527_i235
#ISCELL
  cls offpage_out *
  page527_i236
#ISCELL
  cls offpage_in *
  page527_i237
#ISCELL
  cls gnd_sg *
  page527_i238
#ISCELL
  cls offpage_out *
  page527_i24
#CELL
  passive resistor *
  page527_i240
#CELL
  passive resistor *
  page527_i241
#ISCELL
  cls offpage_out *
  page527_i242
#ISCELL
  cls offpage_in *
  page527_i243
#CELL
  passive fuse *
  page527_i244
#CELL
  passive resistor *
  page527_i245
#ISCELL
  cls offpage_out *
  page527_i246
#ISCELL
  cls offpage_out *
  page527_i247
#ISCELL
  cls offpage_in *
  page527_i25
#ISCELL
  cls offpage_in *
  page527_i26
#ISCELL
  cls offpage_in *
  page527_i27
#ISCELL
  cls offpage_in *
  page527_i28
#CELL
  passive resistor *
  page527_i29
#ISCELL
  cls gnd_sg *
  page527_i3
#CELL
  passive resistor *
  page527_i30
#CELL
  passive resistor *
  page527_i31
#CELL
  passive resistor *
  page527_i32
#CELL
  passive resistor *
  page527_i33
#CELL
  passive resistor *
  page527_i34
#ISCELL
  cls gnd_sg *
  page527_i37
#CELL
  other cl1001485a *
  page527_i4
#ISCELL
  cls gnd_sg *
  page527_i45
#ISCELL
  cls vcc *
  page527_i46
#CELL
  passive capacitor *
  page527_i47
#CELL
  passive capacitor *
  page527_i48
#ISCELL
  cls vcc *
  page527_i49
#ISCELL
  cls gnd_sg *
  page527_i50
#CELL
  passive capacitor *
  page527_i51
#CELL
  passive resistor *
  page527_i52
#CELL
  passive resistor *
  page527_i53
#CELL
  passive resistor *
  page527_i54
#CELL
  passive resistor *
  page527_i55
#CELL
  passive capacitor *
  page527_i56
#CELL
  passive capacitor *
  page527_i57
#ISCELL
  cls offpage_out *
  page527_i6
#ISCELL
  cls offpage_in *
  page527_i62
#ISCELL
  cls offpage_out *
  page527_i63
#ISCELL
  cls offpage_out *
  page527_i64
#ISCELL
  cls offpage_out *
  page527_i65
#CELL
  passive capacitor *
  page527_i66
#ISCELL
  cls offpage_out *
  page527_i7
#ISCELL
  cls gnd_sg *
  page527_i71
#ISCELL
  cls gnd_sg *
  page527_i73
#CELL
  passive capacitor *
  page527_i74
#CELL
  passive capacitor *
  page527_i77
#CELL
  stdlogic tps2051bdbvt_sot23_5 *
  page527_i78
#CELL
  stdlogic tps2051bdbvt_sot23_5 *
  page527_i79
#CELL
  passive resistor *
  page527_i83
#CELL
  passive capacitor *
  page527_i85
#ISCELL
  cls vcc *
  page527_i88
#ISCELL
  cls vcc *
  page527_i89
#CELL
  passive ferritebead *
  page527_i91
#ISCELL
  cls vcc *
  page527_i92
#CELL
  passive capacitor *
  page527_i93
#ISCELL
  cls gnd_sg *
  page527_i96
#ISCELL
  cls sheet_a1 *
  *
#ISCELL
  cls offpage_out *
  page11_i1
#ISCELL
  cls offpage_out *
  page11_i10
#CELL
  passive resistor *
  page11_i11
#CELL
  passive capacitor *
  page11_i12
#CELL
  passive capacitor *
  page11_i13
#ISCELL
  cls gnd_sg *
  page11_i14
#CELL
  passive capacitor *
  page11_i15
#ISCELL
  cls vcc *
  page11_i16
#ISCELL
  cls gnd_sg *
  page11_i17
#CELL
  passive resistor *
  page11_i18
#ISCELL
  cls offpage_out *
  page11_i19
#CELL
  passive resistor *
  page11_i20
#CELL
  passive resistor *
  page11_i21
#ISCELL
  cls gnd_sg *
  page11_i22
#CELL
  passive capacitor *
  page11_i24
#CELL
  passive resistor *
  page11_i25
#CELL
  passive capacitor *
  page11_i26
#ISCELL
  cls offpage_in *
  page11_i28
#CELL
  passive resistor *
  page11_i29
#ISCELL
  cls vcc *
  page11_i32
#CELL
  connector conn_hdr_2x4_f_s_smt *
  page11_i36
#CELL
  passive resistor *
  page11_i38
#ISCELL
  cls vcc *
  page11_i39
#CELL
  passive resistor *
  page11_i40
#ISCELL
  cls vcc *
  page11_i42
#CELL
  passive capacitor *
  page11_i43
#CELL
  passive capacitor *
  page11_i44
#CELL
  passive capacitor *
  page11_i45
#ISCELL
  cls offpage_out *
  page11_i46
#ISCELL
  cls offpage_in *
  page11_i47
#CELL
  passive resistor *
  page11_i5
#ISCELL
  cls vcc *
  page11_i54
#CELL
  passive ferritebead *
  page11_i55
#CELL
  passive ferritebead *
  page11_i56
#ISCELL
  cls offpage_in *
  page11_i57
#CELL
  passive resistor *
  page11_i7
#CELL
  passive resistor *
  page11_i8
#ISCELL
  cls offpage_in *
  page11_i9
#ISCELL
  cls sheet_a1 *
  *
#ISCELL
  cls gnd_sg *
  page12_i120
#CELL
  discrete diode_4_v1 *
  page12_i179
#CELL
  passive resistor *
  page12_i197
#CELL
  stdlogic 74hct2g125dp_tssop8 *
  page12_i204
#CELL
  passive resistor *
  page12_i206
#CELL
  passive capacitor *
  page12_i207
#ISCELL
  cls offpage_in *
  page12_i208
#CELL
  passive resistor *
  page12_i209
#ISCELL
  cls vcc *
  page12_i210
#ISCELL
  cls gnd_sg *
  page12_i211
#ISCELL
  cls offpage_out *
  page12_i212
#CELL
  stdlogic 74hct2g125dp_tssop8 *
  page12_i226
#ISCELL
  cls offpage_out *
  page12_i227
#CELL
  passive resistor *
  page12_i228
#CELL
  passive resistor *
  page12_i229
#ISCELL
  cls vcc *
  page12_i230
#CELL
  passive capacitor *
  page12_i231
#ISCELL
  cls gnd_sg *
  page12_i232
#CELL
  passive resistor *
  page12_i233
#CELL
  passive resistor *
  page12_i234
#ISCELL
  cls vcc *
  page12_i236
#CELL
  passive resistor *
  page12_i237
#ISCELL
  cls offpage_in *
  page12_i239
#ISCELL
  cls offpage_in *
  page12_i240
#ISCELL
  cls offpage_in *
  page12_i241
#CELL
  stdlogic 74hct2g125dp_tssop8 *
  page12_i255
#ISCELL
  cls offpage_out *
  page12_i256
#CELL
  passive resistor *
  page12_i257
#CELL
  passive resistor *
  page12_i258
#ISCELL
  cls vcc *
  page12_i259
#CELL
  passive resistor *
  page12_i261
#CELL
  passive resistor *
  page12_i262
#ISCELL
  cls vcc *
  page12_i264
#CELL
  passive resistor *
  page12_i265
#ISCELL
  cls offpage_in *
  page12_i267
#ISCELL
  cls offpage_in *
  page12_i268
#ISCELL
  cls offpage_in *
  page12_i269
#ISCELL
  cls gnd_sg *
  page12_i271
#CELL
  passive capacitor *
  page12_i272
#CELL
  stdlogic 74hct2g125dp_tssop8 *
  page12_i273
#ISCELL
  cls offpage_out *
  page12_i274
#CELL
  passive resistor *
  page12_i275
#CELL
  passive resistor *
  page12_i276
#ISCELL
  cls vcc *
  page12_i277
#ISCELL
  cls gnd_sg *
  page12_i279
#CELL
  passive resistor *
  page12_i280
#CELL
  passive resistor *
  page12_i281
#ISCELL
  cls vcc *
  page12_i282
#CELL
  passive resistor *
  page12_i284
#ISCELL
  cls offpage_in *
  page12_i286
#ISCELL
  cls offpage_in *
  page12_i287
#ISCELL
  cls offpage_in *
  page12_i288
#CELL
  passive capacitor *
  page12_i289
#CELL
  connector conn_jack_1p_gh4_s_th *
  page12_i290
#ISCELL
  cls gnd_sg *
  page12_i291
#ISCELL
  cls gnd_sg *
  page12_i292
#ISCELL
  cls gnd_sg *
  page12_i293
#CELL
  connector conn_jack_1p_gh4_s_th *
  page12_i294
#ISCELL
  cls gnd_sg *
  page12_i295
#ISCELL
  cls gnd_sg *
  page12_i296
#CELL
  connector conn_jack_1p_gh4_s_th *
  page12_i297
#ISCELL
  cls gnd_sg *
  page12_i298
#ISCELL
  cls gnd_sg *
  page12_i299
#CELL
  connector conn_jack_1p_gh4_s_th *
  page12_i300
#ISCELL
  cls gnd_sg *
  page12_i317
#CELL
  passive capacitor *
  page12_i318
#CELL
  passive resistor *
  page12_i319
#CELL
  passive resistor *
  page12_i320
#CELL
  passive capacitor *
  page12_i321
#CELL
  passive resistor *
  page12_i322
#CELL
  passive resistor *
  page12_i323
#ISCELL
  cls gnd_sg *
  page12_i324
#ISCELL
  cls gnd_sg *
  page12_i325
#CELL
  passive resistor *
  page12_i326
#CELL
  passive resistor *
  page12_i327
#CELL
  passive capacitor *
  page12_i328
#ISCELL
  cls gnd_sg *
  page12_i329
#CELL
  passive resistor *
  page12_i330
#CELL
  passive resistor *
  page12_i331
#CELL
  passive capacitor *
  page12_i332
#ISCELL
  cls gnd_sg *
  page12_i41
#CELL
  discrete diode_4_v1 *
  page12_i42
#ISCELL
  cls gnd_sg *
  page12_i55
#ISCELL
  cls offpage_in *
  page12_i61
#CELL
  passive resistor *
  page12_i63
#ISCELL
  cls offpage_in *
  page12_i79
#CELL
  passive resistor *
  page12_i88
#ISCELL
  cls vcc *
  page12_i89
#ISCELL
  cls sheet_a1 *
  *
#ISCELL
  cls gnd_sg *
  page524_i1
#CELL
  passive capacitor *
  page524_i10
#ISCELL
  cls gnd_sg *
  page524_i102
#CELL
  passive resistor *
  page524_i106
#CELL
  passive ferritebead *
  page524_i118
#ISCELL
  cls gnd_sg *
  page524_i119
#ISCELL
  cls gnd_sg *
  page524_i120
#CELL
  passive resistor *
  page524_i121
#CELL
  passive capacitor *
  page524_i123
#ISCELL
  cls gnd_sg *
  page524_i124
#CELL
  passive ferritebead *
  page524_i127
#CELL
  passive capacitor *
  page524_i128
#ISCELL
  cls offpage_out *
  page524_i135
#ISCELL
  cls offpage_out *
  page524_i136
#ISCELL
  cls offpage_out *
  page524_i137
#ISCELL
  cls offpage_in *
  page524_i138
#CELL
  passive resistor *
  page524_i139
#CELL
  passive resistor *
  page524_i140
#CELL
  passive resistor *
  page524_i141
#CELL
  passive resistor *
  page524_i142
#ISCELL
  cls offpage_out *
  page524_i146
#ISCELL
  cls offpage_in *
  page524_i147
#CELL
  passive resistor *
  page524_i149
#CELL
  passive resistor *
  page524_i150
#CELL
  passive resistor *
  page524_i153
#CELL
  passive resistor *
  page524_i154
#CELL
  passive resistor *
  page524_i166
#CELL
  passive resistor *
  page524_i169
#CELL
  passive resistor *
  page524_i170
#ISCELL
  cls offpage_bi *
  page524_i171
#ISCELL
  cls offpage_out *
  page524_i172
#CELL
  connector g200_10283_01 *
  page524_i173
#ISCELL
  cls offpage_in *
  page524_i176
#CELL
  passive resistor *
  page524_i184
#CELL
  passive resistor *
  page524_i187
#CELL
  passive resistor *
  page524_i188
#CELL
  passive resistor *
  page524_i190
#CELL
  passive resistor *
  page524_i191
#ISCELL
  cls offpage_in *
  page524_i195
#ISCELL
  cls offpage_out *
  page524_i196
#ISCELL
  cls offpage_out *
  page524_i197
#CELL
  passive resistor *
  page524_i198
#CELL
  memory cat93c46vi_gt3_soic8 *
  page524_i200
#CELL
  memory cat93c46vi_gt3_soic8 *
  page524_i201
#ISCELL
  cls gnd_sg *
  page524_i204
#CELL
  passive resistor *
  page524_i206
#CELL
  passive resistor *
  page524_i207
#CELL
  passive resistor *
  page524_i208
#CELL
  passive resistor *
  page524_i23
#ISCELL
  cls gnd_sg *
  page524_i25
#CELL
  passive resistor *
  page524_i26
#CELL
  passive resistor *
  page524_i27
#CELL
  passive resistor *
  page524_i28
#CELL
  passive resistor *
  page524_i287
#ISCELL
  cls gnd_sg *
  page524_i288
#ISCELL
  cls offpage_out *
  page524_i297
#ISCELL
  cls offpage_out *
  page524_i298
#ISCELL
  cls offpage_out *
  page524_i299
#CELL
  other cl1001485a *
  page524_i3
#CELL
  passive resistor *
  page524_i310
#CELL
  cls tp_piont *
  page524_i311
#CELL
  cls tp_piont *
  page524_i312
#CELL
  cls tp_piont *
  page524_i313
#CELL
  cls tp_piont *
  page524_i314
#CELL
  cls tp_piont *
  page524_i315
#CELL
  cls tp_piont *
  page524_i316
#ISCELL
  cls offpage_in *
  page524_i350
#ISCELL
  cls vcc *
  page524_i359
#ISCELL
  cls vcc *
  page524_i360
#ISCELL
  cls vcc *
  page524_i362
#ISCELL
  cls vcc *
  page524_i363
#ISCELL
  cls vcc *
  page524_i364
#ISCELL
  cls vcc *
  page524_i365
#CELL
  passive resistor *
  page524_i368
#ISCELL
  cls offpage_out *
  page524_i370
#CELL
  passive capacitor *
  page524_i373
#CELL
  passive capacitor *
  page524_i374
#CELL
  passive capacitor *
  page524_i375
#CELL
  passive capacitor *
  page524_i376
#CELL
  passive capacitor *
  page524_i377
#CELL
  passive capacitor *
  page524_i378
#CELL
  passive capacitor *
  page524_i379
#CELL
  passive capacitor *
  page524_i380
#ISCELL
  cls offpage_bi *
  page524_i384
#ISCELL
  cls offpage_bi *
  page524_i385
#ISCELL
  cls vcc *
  page524_i386
#ISCELL
  cls offpage_bi *
  page524_i389
#ISCELL
  cls offpage_bi *
  page524_i390
#ISCELL
  cls offpage_bi *
  page524_i391
#ISCELL
  cls offpage_bi *
  page524_i392
#ISCELL
  cls gnd_sg *
  page524_i393
#ISCELL
  cls vcc *
  page524_i394
#CELL
  passive resistor *
  page524_i395
#ISCELL
  cls offpage_out *
  page524_i399
#CELL
  stdlogic ts3a5018pwr_tssop16 *
  page524_i400
#ISCELL
  cls offpage_out *
  page524_i401
#ISCELL
  cls offpage_bi *
  page524_i402
#ISCELL
  cls offpage_bi *
  page524_i403
#ISCELL
  cls offpage_out *
  page524_i404
#ISCELL
  cls offpage_bi *
  page524_i405
#ISCELL
  cls offpage_bi *
  page524_i406
#CELL
  interface nlasb3157dft2g_sc88 *
  page524_i407
#CELL
  interface nlasb3157dft2g_sc88 *
  page524_i408
#ISCELL
  cls offpage_in *
  page524_i409
#ISCELL
  cls offpage_bi *
  page524_i410
#CELL
  passive resistor *
  page524_i411
#CELL
  passive resistor *
  page524_i412
#ISCELL
  cls offpage_bi *
  page524_i413
#ISCELL
  cls offpage_in *
  page524_i414
#ISCELL
  cls offpage_in *
  page524_i415
#ISCELL
  cls offpage_in *
  page524_i416
#ISCELL
  cls offpage_out *
  page524_i417
#ISCELL
  cls offpage_out *
  page524_i418
#ISCELL
  cls offpage_in *
  page524_i419
#ISCELL
  cls offpage_in *
  page524_i420
#ISCELL
  cls offpage_in *
  page524_i421
#ISCELL
  cls offpage_out *
  page524_i422
#CELL
  passive resistor *
  page524_i423
#CELL
  passive resistor *
  page524_i424
#CELL
  stdlogic ts3a5018pwr_tssop16 *
  page524_i425
#ISCELL
  cls offpage_in *
  page524_i426
#ISCELL
  cls offpage_in *
  page524_i427
#ISCELL
  cls offpage_out *
  page524_i428
#ISCELL
  cls offpage_in *
  page524_i429
#CELL
  passive resistor *
  page524_i430
#CELL
  passive resistor *
  page524_i431
#CELL
  passive resistor *
  page524_i432
#ISCELL
  cls offpage_bi *
  page524_i433
#ISCELL
  cls vcc *
  page524_i434
#ISCELL
  cls gnd_sg *
  page524_i435
#ISCELL
  cls offpage_bi *
  page524_i436
#ISCELL
  cls vcc *
  page524_i437
#ISCELL
  cls gnd_sg *
  page524_i438
#ISCELL
  cls offpage_bi *
  page524_i439
#ISCELL
  cls vcc *
  page524_i44
#CELL
  passive resistor *
  page524_i440
#CELL
  passive resistor *
  page524_i441
#CELL
  passive resistor *
  page524_i442
#CELL
  passive resistor *
  page524_i443
#ISCELL
  cls gnd_sg *
  page524_i444
#CELL
  discrete powermos_3p_nch_v1 *
  page524_i445
#CELL
  passive resistor *
  page524_i446
#ISCELL
  cls offpage_in *
  page524_i447
#CELL
  stdlogic ts3a5018pwr_tssop16 *
  page524_i448
#ISCELL
  cls offpage_bi *
  page524_i449
#ISCELL
  cls offpage_out *
  page524_i450
#ISCELL
  cls offpage_bi *
  page524_i451
#ISCELL
  cls offpage_out *
  page524_i452
#ISCELL
  cls offpage_bi *
  page524_i453
#ISCELL
  cls offpage_bi *
  page524_i454
#ISCELL
  cls offpage_in *
  page524_i455
#ISCELL
  cls offpage_in *
  page524_i456
#ISCELL
  cls offpage_bi *
  page524_i457
#ISCELL
  cls offpage_in *
  page524_i458
#CELL
  passive resistor *
  page524_i459
#CELL
  passive resistor *
  page524_i460
#ISCELL
  cls vcc *
  page524_i461
#CELL
  passive resistor *
  page524_i462
#CELL
  passive resistor *
  page524_i463
#CELL
  passive resistor *
  page524_i464
#ISCELL
  cls gnd_sg *
  page524_i465
#CELL
  passive resistor *
  page524_i466
#CELL
  passive resistor *
  page524_i467
#CELL
  passive resistor *
  page524_i468
#CELL
  passive resistor *
  page524_i469
#ISCELL
  cls vcc *
  page524_i470
#ISCELL
  cls offpage_in *
  page524_i471
#ISCELL
  cls offpage_in *
  page524_i472
#CELL
  stdlogic ts3a5018pwr_tssop16 *
  page524_i473
#CELL
  passive capacitor *
  page524_i474
#ISCELL
  cls gnd_sg *
  page524_i475
#CELL
  passive capacitor *
  page524_i476
#CELL
  stdlogic ts3a5018pwr_tssop16 *
  page524_i478
#ISCELL
  cls vcc *
  page524_i479
#ISCELL
  cls gnd_sg *
  page524_i480
#CELL
  stdlogic ts3a5018pwr_tssop16 *
  page524_i481
#CELL
  passive capacitor *
  page524_i482
#ISCELL
  cls gnd_sg *
  page524_i484
#CELL
  interface nlasb3157dft2g_sc88 *
  page524_i485
#CELL
  passive capacitor *
  page524_i486
#ISCELL
  cls vcc *
  page524_i487
#ISCELL
  cls gnd_sg *
  page524_i488
#ISCELL
  cls vcc *
  page524_i489
#CELL
  passive capacitor *
  page524_i490
#CELL
  interface nlasb3157dft2g_sc88 *
  page524_i491
#ISCELL
  cls gnd_sg *
  page524_i492
#CELL
  passive resistor *
  page524_i493
#CELL
  passive resistor *
  page524_i494
#CELL
  connector conn_usb_14p_gh4_f_ra_th *
  page524_i495
#ISCELL
  cls gnd_sg *
  page524_i496
#CELL
  passive resistor *
  page524_i497
#ISCELL
  cls gnd_sg *
  page524_i498
#ISCELL
  cls offpage_in *
  page524_i499
#ISCELL
  cls gnd_sg *
  page524_i5
#ISCELL
  cls offpage_in *
  page524_i501
#ISCELL
  cls offpage_in *
  page524_i502
#ISCELL
  cls gnd_sg *
  page524_i6
#CELL
  interface ft4232hl_reel_qfp64 *
  page524_i64
#CELL
  passive capacitor *
  page524_i7
#CELL
  clock xtal_4 *
  page524_i8
#ISCELL
  cls gnd_sg *
  page524_i9
#ISCELL
  cls gnd_sg *
  page524_i95
#ISCELL
  cls sheet_a1 *
  *
#CELL
  cls tp_piont *
  page16_i1014
#CELL
  cls tp_piont *
  page16_i1015
#CELL
  cls tp_piont *
  page16_i1016
#CELL
  cls tp_piont *
  page16_i1017
#CELL
  cls tp_piont *
  page16_i1018
#CELL
  cls tp_piont *
  page16_i1019
#CELL
  cls tp_piont *
  page16_i1020
#CELL
  cls tp_piont *
  page16_i1021
#CELL
  cls tp_piont *
  page16_i1022
#CELL
  cls tp_piont *
  page16_i1023
#CELL
  cls tp_piont *
  page16_i1206
#ISCELL
  cls vcc *
  page16_i1207
#CELL
  cls tp_piont *
  page16_i1208
#ISCELL
  cls vcc *
  page16_i1209
#CELL
  cls tp_piont *
  page16_i1210
#CELL
  cls tp_piont *
  page16_i1212
#CELL
  cls tp_piont *
  page16_i1215
#CELL
  cls tp_piont *
  page16_i1217
#CELL
  cls tp_piont *
  page16_i1219
#ISCELL
  cls vcc *
  page16_i1220
#ISCELL
  cls vcc *
  page16_i1221
#ISCELL
  cls vcc *
  page16_i1222
#ISCELL
  cls vcc *
  page16_i1223
#ISCELL
  cls vcc *
  page16_i1224
#CELL
  cls tp_piont *
  page16_i1233
#ISCELL
  cls vcc *
  page16_i1234
#ISCELL
  cls offpage_bi *
  page16_i1459
#ISCELL
  cls offpage_bi *
  page16_i1460
#ISCELL
  cls offpage_bi *
  page16_i1461
#ISCELL
  cls offpage_bi *
  page16_i1463
#ISCELL
  cls offpage_bi *
  page16_i1469
#ISCELL
  cls offpage_bi *
  page16_i1477
#ISCELL
  cls offpage_bi *
  page16_i1479
#ISCELL
  cls offpage_bi *
  page16_i1480
#ISCELL
  cls offpage_bi *
  page16_i1481
#ISCELL
  cls offpage_bi *
  page16_i1482
#CELL
  cls tp_piont *
  page16_i1487
#CELL
  cls tp_piont *
  page16_i1488
#CELL
  cls tp_piont *
  page16_i1489
#CELL
  cls tp_piont *
  page16_i1490
#CELL
  cls tp_piont *
  page16_i1505
#CELL
  cls tp_piont *
  page16_i1506
#CELL
  cls tp_piont *
  page16_i1507
#CELL
  cls tp_piont *
  page16_i1508
#CELL
  cls tp_piont *
  page16_i1509
#CELL
  cls tp_piont *
  page16_i1510
#CELL
  cls tp_piont *
  page16_i1511
#CELL
  cls tp_piont *
  page16_i1512
#CELL
  cls tp_piont *
  page16_i1513
#CELL
  cls tp_piont *
  page16_i1516
#ISCELL
  cls offpage_bi *
  page16_i1519
#ISCELL
  cls offpage_bi *
  page16_i1520
#ISCELL
  cls offpage_bi *
  page16_i1521
#ISCELL
  cls offpage_bi *
  page16_i1522
#CELL
  cls tp_piont *
  page16_i1523
#CELL
  cls tp_piont *
  page16_i1524
#CELL
  cls tp_piont *
  page16_i1527
#CELL
  cls tp_piont *
  page16_i1528
#CELL
  cls tp_piont *
  page16_i1529
#CELL
  cls tp_piont *
  page16_i1530
#ISCELL
  cls offpage_bi *
  page16_i1531
#ISCELL
  cls offpage_bi *
  page16_i1534
#ISCELL
  cls offpage_bi *
  page16_i1535
#ISCELL
  cls offpage_bi *
  page16_i1536
#ISCELL
  cls offpage_bi *
  page16_i1537
#ISCELL
  cls offpage_bi *
  page16_i1538
#ISCELL
  cls gnd_sg *
  page16_i1540
#ISCELL
  cls vcc *
  page16_i1541
#CELL
  passive resistor *
  page16_i1542
#CELL
  passive resistor *
  page16_i1544
#CELL
  passive resistor *
  page16_i1547
#CELL
  passive resistor *
  page16_i1549
#CELL
  passive resistor *
  page16_i1550
#CELL
  passive resistor *
  page16_i1552
#CELL
  passive resistor *
  page16_i1555
#CELL
  passive resistor *
  page16_i1557
#ISCELL
  cls offpage_bi *
  page16_i1562
#ISCELL
  cls offpage_bi *
  page16_i1563
#ISCELL
  cls offpage_bi *
  page16_i1564
#ISCELL
  cls offpage_bi *
  page16_i1565
#ISCELL
  cls offpage_bi *
  page16_i1566
#ISCELL
  cls offpage_bi *
  page16_i1567
#ISCELL
  cls offpage_bi *
  page16_i1568
#ISCELL
  cls offpage_bi *
  page16_i1569
#CELL
  passive resistor *
  page16_i1602
#CELL
  passive resistor *
  page16_i1603
#CELL
  passive resistor *
  page16_i1604
#CELL
  passive resistor *
  page16_i1605
#CELL
  passive resistor *
  page16_i1606
#CELL
  passive resistor *
  page16_i1607
#CELL
  passive resistor *
  page16_i1608
#CELL
  passive resistor *
  page16_i1609
#CELL
  cls tp_piont *
  page16_i1610
#ISCELL
  cls vcc *
  page16_i1611
#CELL
  cls tp_piont *
  page16_i1612
#ISCELL
  cls vcc *
  page16_i1613
#CELL
  connector conn_hdr_2x6_f_s_smt *
  page16_i1614
#CELL
  cls tp_piont *
  page16_i1615
#ISCELL
  cls offpage_bi *
  page16_i1616
#ISCELL
  cls offpage_bi *
  page16_i1617
#ISCELL
  cls offpage_bi *
  page16_i1618
#ISCELL
  cls offpage_bi *
  page16_i1619
#ISCELL
  cls offpage_bi *
  page16_i1620
#ISCELL
  cls offpage_bi *
  page16_i1621
#ISCELL
  cls offpage_bi *
  page16_i1622
#ISCELL
  cls offpage_bi *
  page16_i1623
#ISCELL
  cls offpage_bi *
  page16_i1624
#ISCELL
  cls offpage_bi *
  page16_i1625
#CELL
  cls tp_piont *
  page16_i1626
#CELL
  cls tp_piont *
  page16_i1627
#CELL
  cls tp_piont *
  page16_i1628
#CELL
  cls tp_piont *
  page16_i1629
#CELL
  cls tp_piont *
  page16_i1630
#CELL
  cls tp_piont *
  page16_i1631
#CELL
  cls tp_piont *
  page16_i1632
#CELL
  cls tp_piont *
  page16_i1633
#CELL
  cls tp_piont *
  page16_i1634
#ISCELL
  cls offpage_bi *
  page16_i1635
#ISCELL
  cls offpage_bi *
  page16_i1636
#ISCELL
  cls offpage_bi *
  page16_i1637
#ISCELL
  cls offpage_bi *
  page16_i1638
#ISCELL
  cls offpage_bi *
  page16_i1639
#ISCELL
  cls offpage_bi *
  page16_i1640
#ISCELL
  cls offpage_bi *
  page16_i1641
#ISCELL
  cls offpage_bi *
  page16_i1642
#ISCELL
  cls offpage_bi *
  page16_i1643
#ISCELL
  cls offpage_bi *
  page16_i1644
#CELL
  cls tp_piont *
  page16_i1645
#CELL
  cls tp_piont *
  page16_i1646
#CELL
  cls tp_piont *
  page16_i1647
#CELL
  cls tp_piont *
  page16_i1648
#CELL
  cls tp_piont *
  page16_i1649
#CELL
  cls tp_piont *
  page16_i1650
#CELL
  cls tp_piont *
  page16_i1651
#CELL
  cls tp_piont *
  page16_i1652
#CELL
  cls tp_piont *
  page16_i1653
#CELL
  cls tp_piont *
  page16_i1654
#ISCELL
  cls offpage_bi *
  page16_i1656
#ISCELL
  cls offpage_bi *
  page16_i1657
#ISCELL
  cls offpage_bi *
  page16_i1658
#CELL
  cls tp_piont *
  page16_i1660
#CELL
  cls tp_piont *
  page16_i1661
#CELL
  cls tp_piont *
  page16_i1662
#CELL
  cls tp_piont *
  page16_i1663
#ISCELL
  cls offpage_bi *
  page16_i1664
#CELL
  cls tp_piont *
  page16_i1665
#ISCELL
  cls vcc *
  page16_i1666
#CELL
  cls tp_piont *
  page16_i1667
#ISCELL
  cls offpage_bi *
  page16_i1668
#CELL
  cls tp_piont *
  page16_i1669
#ISCELL
  cls offpage_bi *
  page16_i1670
#ISCELL
  cls offpage_bi *
  page16_i1671
#CELL
  cls tp_piont *
  page16_i1672
#CELL
  cls tp_piont *
  page16_i1673
#ISCELL
  cls offpage_bi *
  page16_i1674
#CELL
  cls tp_piont *
  page16_i1675
#ISCELL
  cls offpage_bi *
  page16_i1676
#ISCELL
  cls offpage_bi *
  page16_i1677
#CELL
  cls tp_piont *
  page16_i1678
#CELL
  cls tp_piont *
  page16_i1679
#ISCELL
  cls offpage_bi *
  page16_i1680
#ISCELL
  cls offpage_bi *
  page16_i1681
#CELL
  cls tp_piont *
  page16_i1682
#CELL
  cls tp_piont *
  page16_i1684
#ISCELL
  cls offpage_bi *
  page16_i1685
#ISCELL
  cls offpage_bi *
  page16_i1686
#ISCELL
  cls offpage_bi *
  page16_i1687
#ISCELL
  cls offpage_bi *
  page16_i1688
#CELL
  cls tp_piont *
  page16_i1689
#CELL
  cls tp_piont *
  page16_i1690
#CELL
  cls tp_piont *
  page16_i1691
#ISCELL
  cls offpage_bi *
  page16_i1692
#CELL
  cls tp_piont *
  page16_i1693
#ISCELL
  cls offpage_bi *
  page16_i1694
#CELL
  cls tp_piont *
  page16_i1695
#ISCELL
  cls offpage_bi *
  page16_i1698
#CELL
  cls tp_piont *
  page16_i1699
#ISCELL
  cls offpage_bi *
  page16_i1700
#CELL
  cls tp_piont *
  page16_i1701
#ISCELL
  cls offpage_bi *
  page16_i1702
#ISCELL
  cls offpage_bi *
  page16_i1703
#CELL
  cls tp_piont *
  page16_i1704
#CELL
  cls tp_piont *
  page16_i1705
#CELL
  passive resistor *
  page16_i1706
#CELL
  passive resistor *
  page16_i1707
#CELL
  passive resistor *
  page16_i1708
#CELL
  passive resistor *
  page16_i1709
#CELL
  passive resistor *
  page16_i1718
#CELL
  passive resistor *
  page16_i1719
#CELL
  passive resistor *
  page16_i1720
#CELL
  passive resistor *
  page16_i1721
#ISCELL
  cls vcc *
  page16_i1722
#ISCELL
  cls gnd_sg *
  page16_i1723
#ISCELL
  cls gnd_sg *
  page16_i1724
#ISCELL
  cls offpage_bi *
  page16_i1733
#ISCELL
  cls offpage_bi *
  page16_i1734
#ISCELL
  cls offpage_bi *
  page16_i1735
#ISCELL
  cls offpage_bi *
  page16_i1736
#ISCELL
  cls offpage_bi *
  page16_i1737
#ISCELL
  cls offpage_bi *
  page16_i1738
#ISCELL
  cls offpage_bi *
  page16_i1739
#ISCELL
  cls offpage_bi *
  page16_i1740
#ISCELL
  cls offpage_bi *
  page16_i905
#ISCELL
  cls offpage_bi *
  page16_i906
#ISCELL
  cls offpage_bi *
  page16_i907
#ISCELL
  cls offpage_bi *
  page16_i908
#ISCELL
  cls offpage_bi *
  page16_i909
#ISCELL
  cls offpage_bi *
  page16_i910
#ISCELL
  cls offpage_bi *
  page16_i911
#ISCELL
  cls offpage_bi *
  page16_i912
#ISCELL
  cls offpage_bi *
  page16_i913
#ISCELL
  cls offpage_bi *
  page16_i915
#ISCELL
  cls sheet_a1 *
  *
#ISCELL
  cls offpage_out *
  page14_i104
#CELL
  passive resistor *
  page14_i107
#CELL
  passive resistor *
  page14_i108
#CELL
  discrete optical *
  page14_i11
#CELL
  passive resistor *
  page14_i110
#ISCELL
  cls offpage_out *
  page14_i119
#CELL
  discrete optical *
  page14_i12
#ISCELL
  cls offpage_out *
  page14_i120
#ISCELL
  cls offpage_out *
  page14_i121
#ISCELL
  cls offpage_out *
  page14_i122
#ISCELL
  cls offpage_out *
  page14_i123
#ISCELL
  cls offpage_out *
  page14_i124
#ISCELL
  cls offpage_out *
  page14_i125
#ISCELL
  cls offpage_out *
  page14_i126
#ISCELL
  cls offpage_out *
  page14_i127
#ISCELL
  cls vcc *
  page14_i128
#ISCELL
  cls offpage_out *
  page14_i133
#ISCELL
  cls offpage_out *
  page14_i134
#ISCELL
  cls offpage_out *
  page14_i135
#CELL
  discrete optical *
  page14_i136
#CELL
  discrete optical *
  page14_i137
#CELL
  discrete optical *
  page14_i138
#CELL
  discrete optical *
  page14_i139
#CELL
  discrete optical *
  page14_i140
#CELL
  discrete optical *
  page14_i141
#CELL
  discrete optical *
  page14_i142
#CELL
  discrete optical *
  page14_i143
#CELL
  passive resistor *
  page14_i146
#CELL
  passive resistor *
  page14_i147
#CELL
  passive resistor *
  page14_i148
#CELL
  passive resistor *
  page14_i149
#CELL
  passive resistor *
  page14_i150
#CELL
  passive resistor *
  page14_i151
#CELL
  passive resistor *
  page14_i152
#CELL
  passive resistor *
  page14_i153
#CELL
  passive resistor *
  page14_i154
#CELL
  passive resistor *
  page14_i155
#CELL
  passive resistor *
  page14_i156
#CELL
  passive resistor *
  page14_i157
#ISCELL
  cls offpage_out *
  page14_i159
#CELL
  passive resistor *
  page14_i160
#CELL
  passive resistor *
  page14_i161
#ISCELL
  cls offpage_out *
  page14_i162
#CELL
  passive resistor *
  page14_i163
#ISCELL
  cls offpage_out *
  page14_i164
#CELL
  passive resistor *
  page14_i165
#ISCELL
  cls offpage_out *
  page14_i166
#ISCELL
  cls offpage_out *
  page14_i167
#CELL
  passive resistor *
  page14_i168
#ISCELL
  cls offpage_out *
  page14_i169
#CELL
  passive resistor *
  page14_i170
#CELL
  passive resistor *
  page14_i171
#ISCELL
  cls offpage_out *
  page14_i172
#ISCELL
  cls offpage_out *
  page14_i173
#CELL
  passive resistor *
  page14_i174
#ISCELL
  cls offpage_out *
  page14_i175
#CELL
  passive resistor *
  page14_i176
#CELL
  passive resistor *
  page14_i177
#ISCELL
  cls offpage_out *
  page14_i178
#CELL
  passive resistor *
  page14_i179
#ISCELL
  cls offpage_out *
  page14_i180
#CELL
  passive resistor *
  page14_i181
#ISCELL
  cls offpage_out *
  page14_i182
#ISCELL
  cls offpage_out *
  page14_i183
#CELL
  passive resistor *
  page14_i184
#ISCELL
  cls offpage_out *
  page14_i185
#CELL
  passive resistor *
  page14_i186
#ISCELL
  cls offpage_out *
  page14_i187
#CELL
  passive resistor *
  page14_i188
#CELL
  passive resistor *
  page14_i190
#CELL
  discrete optical *
  page14_i191
#CELL
  passive resistor *
  page14_i192
#CELL
  discrete optical *
  page14_i194
#ISCELL
  cls vcc *
  page14_i195
#ISCELL
  cls vcc *
  page14_i196
#CELL
  interface is32fl3207_qwla3_tr_qfn29 *
  page14_i219
#ISCELL
  cls offpage_out *
  page14_i232
#ISCELL
  cls offpage_out *
  page14_i233
#ISCELL
  cls offpage_out *
  page14_i234
#ISCELL
  cls gnd_sg *
  page14_i235
#ISCELL
  cls vcc *
  page14_i236
#CELL
  passive capacitor *
  page14_i237
#CELL
  passive capacitor *
  page14_i238
#ISCELL
  cls gnd_sg *
  page14_i239
#CELL
  passive resistor *
  page14_i246
#CELL
  passive resistor *
  page14_i247
#ISCELL
  cls gnd_sg *
  page14_i248
#CELL
  passive resistor *
  page14_i249
#CELL
  passive capacitor *
  page14_i250
#ISCELL
  cls gnd_sg *
  page14_i252
#ISCELL
  cls offpage_in *
  page14_i254
#CELL
  passive resistor *
  page14_i257
#CELL
  passive resistor *
  page14_i258
#CELL
  passive resistor *
  page14_i259
#CELL
  passive resistor *
  page14_i261
#ISCELL
  cls offpage_in *
  page14_i262
#ISCELL
  cls offpage_bi *
  page14_i263
#CELL
  passive resistor *
  page14_i264
#CELL
  discrete led_4p_v14 *
  page14_i265
#CELL
  discrete led_4p_v14 *
  page14_i266
#CELL
  discrete led_4p_v14 *
  page14_i267
#CELL
  discrete led_4p_v14 *
  page14_i268
#CELL
  discrete led_4p_v14 *
  page14_i269
#ISCELL
  cls offpage_out *
  page14_i270
#ISCELL
  cls offpage_out *
  page14_i277
#ISCELL
  cls offpage_out *
  page14_i278
#ISCELL
  cls offpage_out *
  page14_i279
#ISCELL
  cls offpage_out *
  page14_i280
#ISCELL
  cls offpage_out *
  page14_i281
#ISCELL
  cls offpage_out *
  page14_i282
#ISCELL
  cls offpage_out *
  page14_i283
#ISCELL
  cls offpage_out *
  page14_i284
#ISCELL
  cls offpage_out *
  page14_i285
#ISCELL
  cls offpage_out *
  page14_i286
#ISCELL
  cls offpage_out *
  page14_i287
#CELL
  passive resistor *
  page14_i288
#CELL
  discrete optical *
  page14_i289
#ISCELL
  cls vcc *
  page14_i290
#ISCELL
  cls offpage_in *
  page14_i291
#CELL
  discrete optical *
  page14_i292
#CELL
  passive resistor *
  page14_i293
#ISCELL
  cls gnd_sg *
  page14_i294
#ISCELL
  cls offpage_in *
  page14_i295
#ISCELL
  cls offpage_bi *
  page14_i296
#ISCELL
  cls offpage_in *
  page14_i297
#CELL
  passive resistor *
  page14_i298
#CELL
  passive resistor *
  page14_i299
#ISCELL
  cls offpage_out *
  page14_i3
#ISCELL
  cls vcc *
  page14_i39
#CELL
  passive resistor *
  page14_i44
#ISCELL
  cls vcc *
  page14_i50
#ISCELL
  cls gnd_sg *
  page14_i51
#ISCELL
  cls vcc *
  page14_i57
#CELL
  passive resistor *
  page14_i58
#ISCELL
  cls vcc *
  page14_i59
#CELL
  passive resistor *
  page14_i60
#ISCELL
  cls vcc *
  page14_i62
#CELL
  passive resistor *
  page14_i63
#CELL
  passive resistor *
  page14_i65
#CELL
  passive resistor *
  page14_i66
#CELL
  passive resistor *
  page14_i67
#CELL
  passive resistor *
  page14_i68
#CELL
  passive resistor *
  page14_i69
#ISCELL
  cls offpage_out *
  page14_i7
#CELL
  passive resistor *
  page14_i70
#CELL
  passive resistor *
  page14_i72
#ISCELL
  cls offpage_out *
  page14_i73
#CELL
  passive resistor *
  page14_i74
#ISCELL
  cls offpage_out *
  page14_i76
#ISCELL
  cls offpage_out *
  page14_i8
#ISCELL
  cls offpage_out *
  page14_i87
#ISCELL
  cls offpage_out *
  page14_i88
#ISCELL
  cls offpage_out *
  page14_i9
#ISCELL
  cls sheet_a1 *
  *
#ISCELL
  cls gnd_sg *
  page15_i148
#CELL
  passive capacitor *
  page15_i156
#ISCELL
  cls gnd_sg *
  page15_i157
#ISCELL
  cls gnd_sg *
  page15_i158
#CELL
  discrete diode_2e *
  page15_i159
#CELL
  passive capacitor *
  page15_i160
#ISCELL
  cls gnd_sg *
  page15_i166
#ISCELL
  cls gnd_sg *
  page15_i167
#ISCELL
  cls gnd_sg *
  page15_i168
#CELL
  passive resistor *
  page15_i169
#CELL
  passive resistor *
  page15_i170
#CELL
  passive resistor *
  page15_i171
#CELL
  passive capacitor *
  page15_i172
#CELL
  passive resistor *
  page15_i173
#CELL
  passive resistor *
  page15_i174
#CELL
  passive resistor *
  page15_i183
#ISCELL
  cls gnd_sg *
  page15_i184
#CELL
  passive capacitor *
  page15_i185
#CELL
  passive resistor *
  page15_i186
#ISCELL
  cls gnd_sg *
  page15_i187
#CELL
  passive resistor *
  page15_i188
#ISCELL
  cls gnd_sg *
  page15_i195
#CELL
  passive capacitor *
  page15_i196
#CELL
  passive resistor *
  page15_i197
#CELL
  passive resistor *
  page15_i198
#CELL
  passive resistor *
  page15_i199
#ISCELL
  cls gnd_sg *
  page15_i200
#CELL
  passive capacitor *
  page15_i201
#CELL
  passive resistor *
  page15_i202
#CELL
  passive resistor *
  page15_i203
#CELL
  discrete diode_2 *
  page15_i204
#ISCELL
  cls gnd_sg *
  page15_i205
#CELL
  passive capacitor *
  page15_i206
#CELL
  passive capacitor *
  page15_i207
#ISCELL
  cls vcc *
  page15_i209
#CELL
  passive capacitor *
  page15_i211
#CELL
  stdlogic mp5022cgqv_z_qfn22 *
  page15_i212
#ISCELL
  cls vcc *
  page15_i213
#ISCELL
  cls vcc *
  page15_i215
#CELL
  passive fuse *
  page15_i223
#ISCELL
  cls gnd_sg *
  page15_i226
#CELL
  passive capacitor *
  page15_i229
#CELL
  passive capacitor *
  page15_i230
#CELL
  passive capacitor *
  page15_i231
#CELL
  passive capacitor *
  page15_i232
#CELL
  connector conn_hdr_2x3_m_ra_th *
  page15_i238
#CELL
  discrete diode_3f *
  page15_i239
#CELL
  passive ferritebead *
  page15_i240
#ISCELL
  cls offpage_in *
  page15_i243
#ISCELL
  cls offpage_out *
  page15_i244
#ISCELL
  cls vcc *
  page15_i245
#ISCELL
  cls offpage_in *
  page15_i246
#ISCELL
  cls sheet_a1 *
  *
#ISCELL
  cls gnd_sg *
  page517_i1
#CELL
  passive resistor *
  page517_i10
#CELL
  passive resistor *
  page517_i11
#CELL
  passive capacitor *
  page517_i12
#CELL
  passive resistor *
  page517_i13
#CELL
  passive capacitor *
  page517_i14
#CELL
  passive capacitor *
  page517_i15
#CELL
  passive capacitor *
  page517_i16
#CELL
  passive capacitor *
  page517_i17
#CELL
  passive resistor *
  page517_i18
#CELL
  passive capacitor *
  page517_i19
#CELL
  passive capacitor *
  page517_i2
#ISCELL
  cls gnd_sg *
  page517_i20
#CELL
  passive capacitor *
  page517_i21
#ISCELL
  cls vcc *
  page517_i22
#ISCELL
  cls gnd_sg *
  page517_i23
#CELL
  mech solder_preform *
  page517_i24
#CELL
  passive resistor *
  page517_i25
#CELL
  passive resistor *
  page517_i26
#CELL
  passive capacitor *
  page517_i27
#CELL
  passive inductor_2 *
  page517_i28
#CELL
  passive capacitor *
  page517_i29
#CELL
  passive resistor *
  page517_i3
#CELL
  passive capacitor *
  page517_i30
#CELL
  passive resistor *
  page517_i31
#CELL
  passive resistor *
  page517_i32
#CELL
  passive resistor *
  page517_i33
#ISCELL
  cls gnd_sg *
  page517_i34
#ISCELL
  cls gnd_sg *
  page517_i35
#CELL
  passive capacitor *
  page517_i36
#CELL
  passive capacitor *
  page517_i37
#CELL
  passive capacitor *
  page517_i38
#ISCELL
  cls vcc *
  page517_i39
#CELL
  passive capacitor *
  page517_i40
#CELL
  passive resistor *
  page517_i41
#CELL
  stdlogic tps54824rnvr_vqfn18 *
  page517_i42
#CELL
  passive resistor *
  page517_i47
#ISCELL
  cls offpage_out *
  page517_i48
#ISCELL
  cls vcc *
  page517_i49
#ISCELL
  cls gnd_sg *
  page517_i5
#CELL
  passive capacitor *
  page517_i51
#ISCELL
  cls offpage_in *
  page517_i52
#CELL
  passive capacitor *
  page517_i6
#CELL
  passive ferritebead *
  page517_i7
#ISCELL
  cls gnd_sg *
  page517_i8
#CELL
  passive capacitor *
  page517_i9
#ISCELL
  cls sheet_a1_enterprise *
  *
#CELL
  passive capacitor *
  page523_i10
#CELL
  passive resistor *
  page523_i104
#ISCELL
  cls offpage_out *
  page523_i105
#ISCELL
  cls gnd_sg *
  page523_i106
#ISCELL
  cls offpage_in *
  page523_i108
#CELL
  passive resistor *
  page523_i109
#CELL
  stdlogic tps54824rnvr_vqfn18 *
  page523_i11
#CELL
  passive capacitor *
  page523_i12
#CELL
  passive capacitor *
  page523_i13
#CELL
  passive capacitor *
  page523_i14
#CELL
  passive resistor *
  page523_i15
#CELL
  passive resistor *
  page523_i16
#CELL
  passive capacitor *
  page523_i17
#ISCELL
  cls gnd_sg *
  page523_i18
#CELL
  passive capacitor *
  page523_i19
#ISCELL
  cls gnd_sg *
  page523_i20
#CELL
  passive resistor *
  page523_i23
#CELL
  passive capacitor *
  page523_i24
#CELL
  passive inductor_2 *
  page523_i25
#CELL
  passive resistor *
  page523_i26
#CELL
  passive capacitor *
  page523_i28
#CELL
  passive resistor *
  page523_i29
#CELL
  passive resistor *
  page523_i30
#CELL
  passive capacitor *
  page523_i31
#ISCELL
  cls gnd_sg *
  page523_i32
#CELL
  passive capacitor *
  page523_i33
#CELL
  passive capacitor *
  page523_i34
#CELL
  passive capacitor *
  page523_i35
#ISCELL
  cls gnd_sg *
  page523_i36
#CELL
  passive capacitor *
  page523_i37
#CELL
  mech solder_preform *
  page523_i39
#ISCELL
  cls vcc *
  page523_i43
#CELL
  passive resistor *
  page523_i44
#ISCELL
  cls gnd_sg *
  page523_i45
#CELL
  passive capacitor *
  page523_i46
#ISCELL
  cls vcc *
  page523_i47
#CELL
  passive ferritebead *
  page523_i48
#CELL
  passive capacitor *
  page523_i50
#CELL
  passive resistor *
  page523_i51
#CELL
  passive resistor *
  page523_i54
#CELL
  passive resistor *
  page523_i56
#CELL
  passive resistor *
  page523_i57
#ISCELL
  cls gnd_sg *
  page523_i6
#CELL
  passive capacitor *
  page523_i7
#CELL
  passive capacitor *
  page523_i9
#ISCELL
  cls vcc *
  page523_i97
#ISCELL
  cls sheet_a1 *
  *
#ISCELL
  cls gnd_sg *
  page68_i1
#CELL
  passive resistor *
  page68_i10
#CELL
  passive resistor *
  page68_i11
#ISCELL
  cls vcc *
  page68_i12
#ISCELL
  cls offpage_out *
  page68_i13
#CELL
  passive resistor *
  page68_i14
#ISCELL
  cls gnd_sg *
  page68_i15
#CELL
  passive resistor *
  page68_i16
#ISCELL
  cls gnd_sg *
  page68_i17
#CELL
  passive resistor *
  page68_i18
#ISCELL
  cls offpage_in *
  page68_i19
#CELL
  passive resistor *
  page68_i2
#ISCELL
  cls vcc *
  page68_i20
#ISCELL
  cls offpage_in *
  page68_i23
#ISCELL
  cls vcc *
  page68_i24
#CELL
  passive ferritebead *
  page68_i25
#CELL
  passive resistor *
  page68_i26
#CELL
  passive capacitor *
  page68_i27
#CELL
  passive capacitor *
  page68_i3
#ISCELL
  cls gnd_sg *
  page68_i34
#CELL
  passive capacitor *
  page68_i35
#ISCELL
  cls gnd_sg *
  page68_i4
#ISCELL
  cls gnd_sg *
  page68_i41
#CELL
  passive resistor *
  page68_i42
#CELL
  passive ferritebead *
  page68_i43
#CELL
  passive resistor *
  page68_i44
#CELL
  passive resistor *
  page68_i45
#CELL
  passive capacitor *
  page68_i46
#CELL
  passive capacitor *
  page68_i47
#ISCELL
  cls gnd_sg *
  page68_i48
#CELL
  passive capacitor *
  page68_i49
#CELL
  passive capacitor *
  page68_i5
#ISCELL
  cls gnd_sg *
  page68_i50
#CELL
  passive capacitor *
  page68_i51
#CELL
  analog isl80101irajz_dfn10 *
  page68_i52
#CELL
  passive resistor *
  page68_i59
#CELL
  analog isl80101irajz_dfn10 *
  page68_i6
#CELL
  passive capacitor *
  page68_i60
#CELL
  passive capacitor *
  page68_i61
#ISCELL
  cls gnd_sg *
  page68_i7
#ISCELL
  cls gnd_sg *
  page68_i70
#CELL
  passive capacitor *
  page68_i71
#ISCELL
  cls gnd_sg *
  page68_i72
#CELL
  passive resistor *
  page68_i73
#CELL
  passive resistor *
  page68_i74
#ISCELL
  cls vcc *
  page68_i75
#ISCELL
  cls gnd_sg *
  page68_i77
#CELL
  passive resistor *
  page68_i78
#CELL
  passive resistor *
  page68_i79
#ISCELL
  cls gnd_sg *
  page68_i8
#CELL
  passive resistor *
  page68_i80
#CELL
  passive capacitor *
  page68_i81
#ISCELL
  cls gnd_sg *
  page68_i82
#CELL
  passive capacitor *
  page68_i83
#ISCELL
  cls vcc *
  page68_i84
#ISCELL
  cls vcc *
  page68_i86
#CELL
  passive capacitor *
  page68_i9
#ISCELL
  cls offpage_out *
  page68_i92
#CELL
  passive capacitor *
  page68_i93
#CELL
  passive capacitor *
  page68_i94
#ISCELL
  cls gnd_sg *
  page68_i95
#ISCELL
  cls gnd_sg *
  page68_i96
#CELL
  passive capacitor *
  page68_i97
#CELL
  passive capacitor *
  page68_i98
#ISCELL
  cls sheet_a1 *
  *
#CELL
  passive resistor *
  page515_i122
#ISCELL
  cls offpage_in *
  page515_i123
#ISCELL
  cls vcc *
  page515_i124
#ISCELL
  cls gnd_sg *
  page515_i126
#CELL
  passive resistor *
  page515_i127
#CELL
  passive capacitor *
  page515_i128
#CELL
  passive resistor *
  page515_i129
#CELL
  passive capacitor *
  page515_i130
#ISCELL
  cls gnd_sg *
  page515_i131
#CELL
  passive capacitor *
  page515_i132
#ISCELL
  cls gnd_sg *
  page515_i133
#CELL
  passive capacitor *
  page515_i134
#CELL
  passive ferritebead *
  page515_i135
#ISCELL
  cls gnd_sg *
  page515_i136
#ISCELL
  cls gnd_sg *
  page515_i137
#CELL
  passive capacitor *
  page515_i138
#CELL
  passive resistor *
  page515_i139
#CELL
  passive resistor *
  page515_i140
#ISCELL
  cls offpage_out *
  page515_i142
#CELL
  passive resistor *
  page515_i143
#ISCELL
  cls gnd_sg *
  page515_i144
#CELL
  passive resistor *
  page515_i145
#CELL
  passive resistor *
  page515_i146
#CELL
  passive capacitor *
  page515_i147
#ISCELL
  cls gnd_sg *
  page515_i148
#CELL
  passive capacitor *
  page515_i149
#ISCELL
  cls vcc *
  page515_i150
#CELL
  analog isl80101irajz_dfn10 *
  page515_i151
#CELL
  passive resistor *
  page515_i152
#ISCELL
  cls gnd_sg *
  page515_i153
#CELL
  passive capacitor *
  page515_i154
#CELL
  passive capacitor *
  page515_i155
#ISCELL
  cls vcc *
  page515_i163
#ISCELL
  cls vcc *
  page515_i164
#ISCELL
  cls offpage_out *
  page515_i166
#CELL
  passive resistor *
  page515_i167
#CELL
  passive capacitor *
  page515_i168
#CELL
  passive capacitor *
  page515_i169
#ISCELL
  cls gnd_sg *
  page515_i55
#CELL
  passive resistor *
  page515_i56
#ISCELL
  cls offpage_in *
  page515_i58
#ISCELL
  cls gnd_sg *
  page515_i60
#CELL
  passive capacitor *
  page515_i61
#CELL
  passive capacitor *
  page515_i63
#CELL
  passive capacitor *
  page515_i64
#ISCELL
  cls gnd_sg *
  page515_i65
#CELL
  passive capacitor *
  page515_i66
#CELL
  passive resistor *
  page515_i67
#CELL
  passive resistor *
  page515_i69
#CELL
  passive capacitor *
  page515_i71
#CELL
  passive capacitor *
  page515_i72
#ISCELL
  cls gnd_sg *
  page515_i73
#CELL
  passive capacitor *
  page515_i74
#ISCELL
  cls vcc *
  page515_i75
#CELL
  analog ncp45560imntwg_h_dfn12 *
  page515_i76
#ISCELL
  cls gnd_sg *
  page515_i77
#CELL
  passive capacitor *
  page515_i80
#CELL
  passive capacitor *
  page515_i81
#CELL
  analog ncp45560imntwg_h_dfn12 *
  page515_i82
#ISCELL
  cls vcc *
  page515_i83
#ISCELL
  cls vcc *
  page515_i85
#ISCELL
  cls vcc *
  page515_i86
#CELL
  passive capacitor *
  page515_i87
#ISCELL
  cls sheet_a1 *
  *
#CELL
  passive resistor *
  page516_i1
#CELL
  passive capacitor *
  page516_i10
#CELL
  passive capacitor *
  page516_i11
#CELL
  passive resistor *
  page516_i12
#CELL
  passive capacitor *
  page516_i13
#CELL
  passive resistor *
  page516_i14
#CELL
  passive capacitor *
  page516_i15
#CELL
  passive resistor *
  page516_i16
#CELL
  passive ferritebead *
  page516_i17
#CELL
  passive capacitor *
  page516_i18
#CELL
  passive capacitor *
  page516_i19
#ISCELL
  cls vcc *
  page516_i2
#CELL
  passive capacitor *
  page516_i20
#ISCELL
  cls gnd_sg *
  page516_i21
#CELL
  passive capacitor *
  page516_i22
#ISCELL
  cls gnd_sg *
  page516_i23
#CELL
  mech solder_preform *
  page516_i24
#CELL
  passive resistor *
  page516_i25
#CELL
  passive resistor *
  page516_i26
#CELL
  passive capacitor *
  page516_i27
#CELL
  passive resistor *
  page516_i28
#CELL
  passive capacitor *
  page516_i29
#ISCELL
  cls gnd_sg *
  page516_i3
#CELL
  passive resistor *
  page516_i30
#CELL
  passive resistor *
  page516_i31
#CELL
  passive capacitor *
  page516_i32
#CELL
  passive capacitor *
  page516_i33
#ISCELL
  cls gnd_sg *
  page516_i34
#CELL
  passive capacitor *
  page516_i35
#CELL
  passive inductor_2 *
  page516_i36
#CELL
  passive capacitor *
  page516_i37
#CELL
  passive resistor *
  page516_i38
#ISCELL
  cls gnd_sg *
  page516_i39
#CELL
  passive capacitor *
  page516_i4
#CELL
  passive capacitor *
  page516_i40
#ISCELL
  cls vcc *
  page516_i41
#CELL
  stdlogic tps54824rnvr_vqfn18 *
  page516_i42
#ISCELL
  cls offpage_in *
  page516_i43
#CELL
  passive resistor *
  page516_i44
#CELL
  passive resistor *
  page516_i45
#ISCELL
  cls offpage_out *
  page516_i46
#ISCELL
  cls vcc *
  page516_i5
#ISCELL
  cls gnd_sg *
  page516_i6
#CELL
  passive capacitor *
  page516_i7
#ISCELL
  cls gnd_sg *
  page516_i8
#CELL
  passive resistor *
  page516_i9
#ISCELL
  cls sheet_a1 *
  *
#CELL
  passive ferritebead *
  page525_i10
#CELL
  discrete diode_2f *
  page525_i102
#CELL
  discrete diode_2f *
  page525_i104
#ISCELL
  cls vcc *
  page525_i105
#ISCELL
  cls vcc *
  page525_i107
#CELL
  passive ferritebead *
  page525_i108
#ISCELL
  cls gnd_sg *
  page525_i11
#CELL
  passive resistor *
  page525_i13
#CELL
  passive capacitor *
  page525_i14
#CELL
  passive capacitor *
  page525_i16
#ISCELL
  cls gnd_sg *
  page525_i17
#CELL
  passive capacitor *
  page525_i18
#ISCELL
  cls gnd_sg *
  page525_i19
#CELL
  passive capacitor *
  page525_i20
#CELL
  analog isl80101irajz_dfn10 *
  page525_i29
#ISCELL
  cls gnd_sg *
  page525_i30
#ISCELL
  cls gnd_sg *
  page525_i35
#ISCELL
  cls gnd_sg *
  page525_i55
#CELL
  passive capacitor *
  page525_i56
#ISCELL
  cls gnd_sg *
  page525_i6
#CELL
  passive capacitor *
  page525_i64
#CELL
  passive resistor *
  page525_i65
#CELL
  passive resistor *
  page525_i66
#CELL
  passive resistor *
  page525_i67
#CELL
  passive resistor *
  page525_i68
#ISCELL
  cls vcc *
  page525_i69
#CELL
  passive capacitor *
  page525_i7
#CELL
  passive capacitor *
  page525_i8
#ISCELL
  cls offpage_out *
  page525_i82
#ISCELL
  cls vcc *
  page525_i9
#ISCELL
  cls sheet_a1 *
  *
#CELL
  mech mec_mth8 *
  page33_i1
#CELL
  mech mec_npth *
  page33_i120
#CELL
  mech mec_npth *
  page33_i121
#CELL
  mech mec_npth *
  page33_i122
#CELL
  mech mec_npth *
  page33_i123
#ISCELL
  cls gnd_sg *
  page33_i124
#CELL
  mech nut *
  page33_i125
#CELL
  mech nut *
  page33_i126
#CELL
  mech nut *
  page33_i127
#ISCELL
  cls gnd_sg *
  page33_i128
#CELL
  mech nut *
  page33_i129
#CELL
  mech solder_preform *
  page33_i130
#CELL
  mech solder_preform *
  page33_i131
#CELL
  mech solder_preform *
  page33_i132
#CELL
  mech solder_preform *
  page33_i133
#CELL
  mech solder_preform *
  page33_i134
#CELL
  mech solder_preform *
  page33_i135
#CELL
  mech solder_preform *
  page33_i136
#CELL
  mech solder_preform *
  page33_i137
#CELL
  mech solder_preform *
  page33_i138
#CELL
  mech solder_preform *
  page33_i139
#CELL
  mech solder_preform *
  page33_i140
#CELL
  mech solder_preform *
  page33_i141
#CELL
  mech solder_preform *
  page33_i142
#CELL
  mech solder_preform *
  page33_i143
#CELL
  mech solder_preform *
  page33_i144
#CELL
  mech solder_preform *
  page33_i145
#CELL
  mech solder_preform *
  page33_i146
#CELL
  mech solder_preform *
  page33_i147
#CELL
  mech solder_preform *
  page33_i148
#CELL
  mech solder_preform *
  page33_i149
#CELL
  mech solder_preform *
  page33_i150
#CELL
  mech solder_preform *
  page33_i151
#CELL
  mech solder_preform *
  page33_i152
#CELL
  mech solder_preform *
  page33_i153
#CELL
  mech solder_preform *
  page33_i155
#CELL
  mech solder_preform *
  page33_i159
#CELL
  mech solder_preform *
  page33_i161
#CELL
  mech solder_preform *
  page33_i163
#CELL
  mech solder_preform *
  page33_i165
#CELL
  mech solder_preform *
  page33_i167
#CELL
  mech solder_preform *
  page33_i169
#CELL
  mech solder_preform *
  page33_i171
#CELL
  mech solder_preform *
  page33_i172
#CELL
  mech solder_preform *
  page33_i173
#CELL
  mech solder_preform *
  page33_i174
#CELL
  mech solder_preform *
  page33_i175
#CELL
  mech solder_preform *
  page33_i176
#CELL
  mech solder_preform *
  page33_i177
#CELL
  mech mec_mth8 *
  page33_i2
#ISCELL
  cls gnd_sg *
  page33_i3
#ISCELL
  cls gnd_sg *
  page33_i4
#CELL
  mech null *
  page33_i47
#CELL
  mech null *
  page33_i48
#CELL
  mech null *
  page33_i49
#CELL
  mech mec_mth8 *
  page33_i5
#CELL
  mech null *
  page33_i50
#CELL
  mech null *
  page33_i51
#CELL
  mech null *
  page33_i52
#CELL
  mech null *
  page33_i53
#CELL
  mech null *
  page33_i54
#CELL
  mech null *
  page33_i55
#CELL
  mech null *
  page33_i56
#CELL
  mech null *
  page33_i57
#CELL
  mech null *
  page33_i58
#CELL
  mech null *
  page33_i59
#ISCELL
  cls gnd_sg *
  page33_i6
#CELL
  mech null *
  page33_i60
#CELL
  mech null *
  page33_i61
#CELL
  mech null *
  page33_i62
#CELL
  mech null *
  page33_i63
#CELL
  mech null *
  page33_i64
#CELL
  mech null *
  page33_i65
#CELL
  mech null *
  page33_i66
#CELL
  mech null *
  page33_i67
#CELL
  mech null *
  page33_i68
#CELL
  mech null *
  page33_i69
#CELL
  mech mec_mth8 *
  page33_i7
#CELL
  mech null *
  page33_i70
#ISCELL
  cls gnd_sg *
  page33_i8
#CELL
  mech null *
  page33_i83
#CELL
  mech null *
  page33_i84
#CELL
  mech null *
  page33_i85
#CELL
  mech null *
  page33_i89
#CELL
  mech null *
  page33_i90
#CELL
  mech null *
  page33_i93
#ISCELL
  cls table_toc_cl *
  *
